FILE_TYPE = MACRO_DRAWING;
SET COLOR_WIRE YELLOW;
SET COLOR_PROP MONO;
SET COLOR_DOT WHITE;
SET COLOR_ARC YELLOW;
SET COLOR_BODY GREEN;
SET COLOR_NOTE MONO;
SET PROP_DISPLAY VALUE;
SET PAGE_NUMBER P21;
FORCEADD OFFPAGE..5
(-6350 3850);
FORCEPROP 2 LAST $XR0 49 
J 0
(-6574 3850);
DISPLAY 0.638298 (-6574 3850);
PAINT MONO (-6574 3850);
FORCEPROP 2 LAST $XR1 50 
J 0
(-6664 3850);
DISPLAY 0.638298 (-6664 3850);
PAINT MONO (-6664 3850);
FORCEPROP 2 LAST $XR2 51 
J 0
(-6754 3850);
DISPLAY 0.638298 (-6754 3850);
PAINT MONO (-6754 3850);
FORCEPROP 2 LAST $XR3 52 
J 0
(-6844 3850);
DISPLAY 0.638298 (-6844 3850);
PAINT MONO (-6844 3850);
FORCEPROP 2 LAST $XR4 53 
J 0
(-6934 3850);
DISPLAY 0.638298 (-6934 3850);
PAINT MONO (-6934 3850);
FORCEPROP 2 LAST $XR5 54 
J 0
(-7024 3850);
DISPLAY 0.638298 (-7024 3850);
PAINT MONO (-7024 3850);
FORCEPROP 2 LAST CDS_LIB mstr_standard
J 0
(-6350 3850);
PAINT MONO (-6350 3850);
DISPLAY INVISIBLE (-6350 3850);
FORCEPROP 2 LAST PATH I10
J 0
(-6300 3925);
DISPLAY 1.361702 (-6300 3925);
PAINT ORANGE (-6300 3925);
DISPLAY INVISIBLE (-6300 3925);
FORCEPROP 1 LAST OFFPAGE TRUE
J 0
(-6025 3725);
DISPLAY 1.170213 (-6025 3725);
PAINT GREEN (-6025 3725);
DISPLAY INVISIBLE (-6025 3725);
FORCEPROP 1 LAST COMMENT_BODY TRUE
J 0
(-6250 3775);
DISPLAY 1.170213 (-6250 3775);
PAINT PEACH (-6250 3775);
DISPLAY INVISIBLE (-6250 3775);
FORCEADD OFFPAGE..2
(-1800 1150);
FORCEPROP 2 LAST $XR0 112 
J 0
(-1611 1150);
DISPLAY 0.638298 (-1611 1150);
PAINT MONO (-1611 1150);
FORCEPROP 2 LAST CDS_LIB mstr_standard
J 0
(-1800 1150);
PAINT MONO (-1800 1150);
DISPLAY INVISIBLE (-1800 1150);
FORCEPROP 2 LAST PATH I106
J 0
(-1625 1225);
DISPLAY 1.361702 (-1625 1225);
PAINT ORANGE (-1625 1225);
DISPLAY INVISIBLE (-1625 1225);
FORCEPROP 1 LAST OFFPAGE TRUE
J 0
(-1475 1025);
DISPLAY 1.170213 (-1475 1025);
PAINT GREEN (-1475 1025);
DISPLAY INVISIBLE (-1475 1025);
FORCEPROP 1 LAST COMMENT_BODY TRUE
J 0
(-1845 1055);
DISPLAY 1.170213 (-1845 1055);
PAINT PEACH (-1845 1055);
DISPLAY INVISIBLE (-1845 1055);
FORCEADD OFFPAGE..4
(-1850 4500);
FORCEPROP 2 LAST $XR0 96 
J 0
(-1664 4500);
DISPLAY 0.638298 (-1664 4500);
PAINT MONO (-1664 4500);
FORCEPROP 2 LAST $XR1 113 
J 0
(-1574 4500);
DISPLAY 0.638298 (-1574 4500);
PAINT MONO (-1574 4500);
FORCEPROP 2 LAST CDS_LIB mstr_standard
J 0
(-1850 4500);
PAINT MONO (-1850 4500);
DISPLAY INVISIBLE (-1850 4500);
FORCEPROP 2 LAST PATH I107
J 0
(-1675 4575);
DISPLAY 1.361702 (-1675 4575);
PAINT ORANGE (-1675 4575);
DISPLAY INVISIBLE (-1675 4575);
FORCEPROP 1 LAST OFFPAGE TRUE
J 0
(-1525 4375);
DISPLAY 1.170213 (-1525 4375);
PAINT GREEN (-1525 4375);
DISPLAY INVISIBLE (-1525 4375);
FORCEPROP 1 LAST COMMENT_BODY TRUE
J 0
(-1875 4400);
DISPLAY 1.170213 (-1875 4400);
PAINT PEACH (-1875 4400);
DISPLAY INVISIBLE (-1875 4400);
FORCEADD OFFPAGE..1
R 2
(-1850 4450);
FORCEPROP 2 LAST $XR0 96 
J 0
(-1664 4450);
DISPLAY 0.638298 (-1664 4450);
PAINT MONO (-1664 4450);
FORCEPROP 2 LAST CDS_LIB mstr_standard
J 2
(-1850 4450);
PAINT MONO (-1850 4450);
DISPLAY INVISIBLE (-1850 4450);
FORCEPROP 2 LAST PATH I108
J 2
(-2025 4525);
DISPLAY 1.361702 (-2025 4525);
PAINT ORANGE (-2025 4525);
DISPLAY INVISIBLE (-2025 4525);
FORCEPROP 1 LAST OFFPAGE TRUE
J 2
(-2175 4325);
DISPLAY 0.872340 (-2175 4325);
PAINT GREEN (-2175 4325);
DISPLAY INVISIBLE (-2175 4325);
FORCEPROP 1 LAST COMMENT_BODY TRUE
J 2
(-1975 4350);
DISPLAY 0.872340 (-1975 4350);
PAINT GREEN (-1975 4350);
DISPLAY INVISIBLE (-1975 4350);
FORCEADD OFFPAGE..1
(-6325 3750);
FORCEPROP 2 LAST $XR0 94 
J 0
(-6576 3750);
DISPLAY 0.638298 (-6576 3750);
PAINT MONO (-6576 3750);
FORCEPROP 2 LAST $XR1 95 
J 0
(-6666 3750);
DISPLAY 0.638298 (-6666 3750);
PAINT MONO (-6666 3750);
FORCEPROP 2 LAST $XR2 152 
J 0
(-6786 3750);
DISPLAY 0.638298 (-6786 3750);
PAINT MONO (-6786 3750);
FORCEPROP 2 LAST CDS_LIB mstr_standard
J 0
(-6325 3750);
PAINT MONO (-6325 3750);
DISPLAY INVISIBLE (-6325 3750);
FORCEPROP 2 LAST PATH I11
J 0
(-6275 3825);
DISPLAY 1.361702 (-6275 3825);
PAINT ORANGE (-6275 3825);
DISPLAY INVISIBLE (-6275 3825);
FORCEPROP 1 LAST OFFPAGE TRUE
J 0
(-6000 3625);
DISPLAY 0.872340 (-6000 3625);
PAINT GREEN (-6000 3625);
DISPLAY INVISIBLE (-6000 3625);
FORCEPROP 1 LAST COMMENT_BODY TRUE
J 0
(-6200 3650);
DISPLAY 0.872340 (-6200 3650);
PAINT GREEN (-6200 3650);
DISPLAY INVISIBLE (-6200 3650);
FORCEADD OFFPAGE..3
(-1825 3350);
FORCEPROP 2 LAST $XR0 92 
J 0
(-1611 3350);
DISPLAY 0.638298 (-1611 3350);
PAINT MONO (-1611 3350);
FORCEPROP 2 LAST CDS_LIB mstr_standard
J 0
(-1825 3350);
PAINT MONO (-1825 3350);
DISPLAY INVISIBLE (-1825 3350);
FORCEPROP 2 LAST PATH I111
J 0
(-1650 3425);
DISPLAY 1.361702 (-1650 3425);
PAINT ORANGE (-1650 3425);
DISPLAY INVISIBLE (-1650 3425);
FORCEPROP 1 LAST OFFPAGE TRUE
J 0
(-1500 3225);
DISPLAY 1.170213 (-1500 3225);
PAINT GREEN (-1500 3225);
DISPLAY INVISIBLE (-1500 3225);
FORCEPROP 1 LAST COMMENT_BODY TRUE
J 0
(-1875 3250);
DISPLAY 1.170213 (-1875 3250);
PAINT PEACH (-1875 3250);
DISPLAY INVISIBLE (-1875 3250);
FORCEADD OFFPAGE..1
(-6325 3700);
FORCEPROP 2 LAST $XR0 94 
J 0
(-6576 3700);
DISPLAY 0.638298 (-6576 3700);
PAINT MONO (-6576 3700);
FORCEPROP 2 LAST $XR1 95 
J 0
(-6666 3700);
DISPLAY 0.638298 (-6666 3700);
PAINT MONO (-6666 3700);
FORCEPROP 2 LAST $XR2 152 
J 0
(-6786 3700);
DISPLAY 0.638298 (-6786 3700);
PAINT MONO (-6786 3700);
FORCEPROP 2 LAST CDS_LIB mstr_standard
J 0
(-6325 3700);
PAINT MONO (-6325 3700);
DISPLAY INVISIBLE (-6325 3700);
FORCEPROP 2 LAST PATH I12
J 0
(-6275 3775);
DISPLAY 1.361702 (-6275 3775);
PAINT ORANGE (-6275 3775);
DISPLAY INVISIBLE (-6275 3775);
FORCEPROP 1 LAST OFFPAGE TRUE
J 0
(-6000 3575);
DISPLAY 0.872340 (-6000 3575);
PAINT GREEN (-6000 3575);
DISPLAY INVISIBLE (-6000 3575);
FORCEPROP 1 LAST COMMENT_BODY TRUE
J 0
(-6200 3600);
DISPLAY 0.872340 (-6200 3600);
PAINT GREEN (-6200 3600);
DISPLAY INVISIBLE (-6200 3600);
FORCEADD OFFPAGE..5
(-6025 2900);
FORCEPROP 2 LAST $XR0 99 
J 0
(-6279 2900);
DISPLAY 0.638298 (-6279 2900);
PAINT MONO (-6279 2900);
FORCEPROP 2 LAST CDS_LIB mstr_standard
J 0
(-6025 2900);
PAINT MONO (-6025 2900);
DISPLAY INVISIBLE (-6025 2900);
FORCEPROP 2 LAST PATH I133
J 0
(-6225 2950);
DISPLAY 1.361702 (-6225 2950);
PAINT ORANGE (-6225 2950);
DISPLAY INVISIBLE (-6225 2950);
FORCEPROP 1 LAST OFFPAGE TRUE
J 0
(-5700 2775);
DISPLAY 1.170213 (-5700 2775);
PAINT GREEN (-5700 2775);
DISPLAY INVISIBLE (-5700 2775);
FORCEPROP 1 LAST COMMENT_BODY TRUE
J 0
(-5925 2825);
DISPLAY 1.170213 (-5925 2825);
PAINT PEACH (-5925 2825);
DISPLAY INVISIBLE (-5925 2825);
FORCEADD OFFPAGE..5
(-6025 2850);
FORCEPROP 2 LAST $XR0 99 
J 0
(-6279 2850);
DISPLAY 0.638298 (-6279 2850);
PAINT MONO (-6279 2850);
FORCEPROP 2 LAST CDS_LIB mstr_standard
J 0
(-6025 2850);
PAINT MONO (-6025 2850);
DISPLAY INVISIBLE (-6025 2850);
FORCEPROP 2 LAST PATH I134
J 0
(-6225 2900);
DISPLAY 1.361702 (-6225 2900);
PAINT ORANGE (-6225 2900);
DISPLAY INVISIBLE (-6225 2900);
FORCEPROP 1 LAST OFFPAGE TRUE
J 0
(-5700 2725);
DISPLAY 1.170213 (-5700 2725);
PAINT GREEN (-5700 2725);
DISPLAY INVISIBLE (-5700 2725);
FORCEPROP 1 LAST COMMENT_BODY TRUE
J 0
(-5925 2775);
DISPLAY 1.170213 (-5925 2775);
PAINT PEACH (-5925 2775);
DISPLAY INVISIBLE (-5925 2775);
FORCEADD OFFPAGE..5
(-6025 2800);
FORCEPROP 2 LAST $XR0 99 
J 0
(-6279 2800);
DISPLAY 0.638298 (-6279 2800);
PAINT MONO (-6279 2800);
FORCEPROP 2 LAST CDS_LIB mstr_standard
J 0
(-6025 2800);
PAINT MONO (-6025 2800);
DISPLAY INVISIBLE (-6025 2800);
FORCEPROP 2 LAST PATH I135
J 0
(-6225 2850);
DISPLAY 1.361702 (-6225 2850);
PAINT ORANGE (-6225 2850);
DISPLAY INVISIBLE (-6225 2850);
FORCEPROP 1 LAST OFFPAGE TRUE
J 0
(-5700 2675);
DISPLAY 1.170213 (-5700 2675);
PAINT GREEN (-5700 2675);
DISPLAY INVISIBLE (-5700 2675);
FORCEPROP 1 LAST COMMENT_BODY TRUE
J 0
(-5925 2725);
DISPLAY 1.170213 (-5925 2725);
PAINT PEACH (-5925 2725);
DISPLAY INVISIBLE (-5925 2725);
FORCEADD OFFPAGE..5
(-6025 2750);
FORCEPROP 2 LAST $XR0 99 
J 0
(-6279 2750);
DISPLAY 0.638298 (-6279 2750);
PAINT MONO (-6279 2750);
FORCEPROP 2 LAST CDS_LIB mstr_standard
J 0
(-6025 2750);
PAINT MONO (-6025 2750);
DISPLAY INVISIBLE (-6025 2750);
FORCEPROP 2 LAST PATH I136
J 0
(-6225 2800);
DISPLAY 1.361702 (-6225 2800);
PAINT ORANGE (-6225 2800);
DISPLAY INVISIBLE (-6225 2800);
FORCEPROP 1 LAST OFFPAGE TRUE
J 0
(-5700 2625);
DISPLAY 1.170213 (-5700 2625);
PAINT GREEN (-5700 2625);
DISPLAY INVISIBLE (-5700 2625);
FORCEPROP 1 LAST COMMENT_BODY TRUE
J 0
(-5925 2675);
DISPLAY 1.170213 (-5925 2675);
PAINT PEACH (-5925 2675);
DISPLAY INVISIBLE (-5925 2675);
FORCEADD OFFPAGE..3
(-1825 4100);
FORCEPROP 2 LAST $XR0 55 
J 0
(-1611 4100);
DISPLAY 0.638298 (-1611 4100);
PAINT MONO (-1611 4100);
FORCEPROP 2 LAST $XR1 166 
J 0
(-1521 4100);
DISPLAY 0.638298 (-1521 4100);
PAINT MONO (-1521 4100);
FORCEPROP 2 LAST CDS_LIB mstr_standard
J 0
(-1825 4100);
PAINT MONO (-1825 4100);
DISPLAY INVISIBLE (-1825 4100);
FORCEPROP 2 LAST PATH I137
J 0
(-1650 4175);
DISPLAY 1.361702 (-1650 4175);
PAINT ORANGE (-1650 4175);
DISPLAY INVISIBLE (-1650 4175);
FORCEPROP 1 LAST OFFPAGE TRUE
J 0
(-1500 3975);
DISPLAY 1.170213 (-1500 3975);
PAINT GREEN (-1500 3975);
DISPLAY INVISIBLE (-1500 3975);
FORCEPROP 1 LAST COMMENT_BODY TRUE
J 0
(-1875 4000);
DISPLAY 1.170213 (-1875 4000);
PAINT PEACH (-1875 4000);
DISPLAY INVISIBLE (-1875 4000);
FORCEADD OFFPAGE..3
(-775 3850);
FORCEPROP 2 LAST $XR0 194 
J 0
(-561 3850);
DISPLAY 0.638298 (-561 3850);
PAINT MONO (-561 3850);
FORCEPROP 2 LAST $XR1 201 
J 0
(-441 3850);
DISPLAY 0.638298 (-441 3850);
PAINT MONO (-441 3850);
FORCEPROP 2 LAST $XR2 211 
J 0
(-321 3850);
DISPLAY 0.638298 (-321 3850);
PAINT MONO (-321 3850);
FORCEPROP 2 LAST CDS_LIB mstr_standard
J 0
(-775 3850);
PAINT MONO (-775 3850);
DISPLAY INVISIBLE (-775 3850);
FORCEPROP 2 LAST PATH I145
J 0
(-575 3925);
DISPLAY 1.361702 (-575 3925);
PAINT ORANGE (-575 3925);
DISPLAY INVISIBLE (-575 3925);
FORCEPROP 1 LAST OFFPAGE TRUE
J 0
(-450 3725);
DISPLAY 1.170213 (-450 3725);
PAINT GREEN (-450 3725);
DISPLAY INVISIBLE (-450 3725);
FORCEPROP 1 LAST COMMENT_BODY TRUE
J 0
(-825 3750);
DISPLAY 1.170213 (-825 3750);
PAINT PEACH (-825 3750);
DISPLAY INVISIBLE (-825 3750);
FORCEADD OFFPAGE..2
(-750 3800);
FORCEPROP 2 LAST $XR0 194 
J 0
(-561 3800);
DISPLAY 0.638298 (-561 3800);
PAINT MONO (-561 3800);
FORCEPROP 2 LAST $XR1 201 
J 0
(-441 3800);
DISPLAY 0.638298 (-441 3800);
PAINT MONO (-441 3800);
FORCEPROP 2 LAST $XR2 211 
J 0
(-321 3800);
DISPLAY 0.638298 (-321 3800);
PAINT MONO (-321 3800);
FORCEPROP 2 LAST CDS_LIB mstr_standard
J 0
(-750 3800);
PAINT MONO (-750 3800);
DISPLAY INVISIBLE (-750 3800);
FORCEPROP 2 LAST PATH I146
J 0
(-200 3850);
DISPLAY 1.361702 (-200 3850);
PAINT ORANGE (-200 3850);
DISPLAY INVISIBLE (-200 3850);
FORCEPROP 1 LAST OFFPAGE TRUE
J 0
(-425 3675);
DISPLAY 1.170213 (-425 3675);
PAINT GREEN (-425 3675);
DISPLAY INVISIBLE (-425 3675);
FORCEPROP 1 LAST COMMENT_BODY TRUE
J 0
(-795 3705);
DISPLAY 1.170213 (-795 3705);
PAINT PEACH (-795 3705);
DISPLAY INVISIBLE (-795 3705);
FORCEADD OFFPAGE..4
(-750 3750);
FORCEPROP 2 LAST $XR0 194 
J 0
(-564 3750);
DISPLAY 0.638298 (-564 3750);
PAINT MONO (-564 3750);
FORCEPROP 2 LAST $XR1 201 
J 0
(-444 3750);
DISPLAY 0.638298 (-444 3750);
PAINT MONO (-444 3750);
FORCEPROP 2 LAST $XR2 211 
J 0
(-324 3750);
DISPLAY 0.638298 (-324 3750);
PAINT MONO (-324 3750);
FORCEPROP 2 LAST CDS_LIB mstr_standard
J 0
(-750 3750);
PAINT MONO (-750 3750);
DISPLAY INVISIBLE (-750 3750);
FORCEPROP 2 LAST PATH I147
J 0
(-575 3825);
DISPLAY 1.361702 (-575 3825);
PAINT ORANGE (-575 3825);
DISPLAY INVISIBLE (-575 3825);
FORCEPROP 1 LAST OFFPAGE TRUE
J 0
(-425 3625);
DISPLAY 1.170213 (-425 3625);
PAINT GREEN (-425 3625);
DISPLAY INVISIBLE (-425 3625);
FORCEPROP 1 LAST COMMENT_BODY TRUE
J 0
(-775 3650);
DISPLAY 1.170213 (-775 3650);
PAINT PEACH (-775 3650);
DISPLAY INVISIBLE (-775 3650);
FORCEADD RES..1
(-1975 3750);
FORCEPROP 1 LAST LOCATION R6N10
J 0
(-2450 3750);
DISPLAY 0.617021 (-2450 3750);
PAINT AQUA (-2450 3750);
FORCEPROP 1 LAST PART_NUMBER G21796-271
J 0
(-2325 3750);
DISPLAY 0.617021 (-2325 3750);
PAINT BLUE (-2325 3750);
FORCEPROP 1 LAST VALUE 221
J 2
(-1775 3725);
DISPLAY 0.617021 (-1775 3725);
PAINT SKYBLUE (-1775 3725);
FORCEPROP 1 LAST TOLERANCE 1.0%
J 0
(-1775 3725);
DISPLAY 0.617021 (-1775 3725);
PAINT SKYBLUE (-1775 3725);
FORCEPROP 1 LAST PACK_TYPE 0402
J 0
(-1675 3725);
DISPLAY 0.617021 (-1675 3725);
PAINT SKYBLUE (-1675 3725);
FORCEPROP 1 LASTPIN (-1875 3750) $PN 2
J 0
(-1913 3762);
DISPLAY 0.617021 (-1913 3762);
PAINT WHITE (-1913 3762);
FORCEPROP 1 LASTPIN (-2075 3750) $PN 1
J 0
(-2063 3762);
DISPLAY 0.617021 (-2063 3762);
PAINT WHITE (-2063 3762);
FORCEPROP 1 LAST MATERIAL CHIP
J 0
(-1825 3650);
DISPLAY 0.510638 (-1825 3650);
PAINT SKYBLUE (-1825 3650);
DISPLAY INVISIBLE (-1825 3650);
FORCEPROP 1 LAST WATTAGE 1/16W
J 2
(-1450 3725);
DISPLAY 0.510638 (-1450 3725);
PAINT SKYBLUE (-1450 3725);
DISPLAY INVISIBLE (-1450 3725);
FORCEPROP 2 LAST CDS_LIB mstr_discrete
J 0
(-1975 3750);
DISPLAY 1.340426 (-1975 3750);
PAINT ORANGE (-1975 3750);
DISPLAY INVISIBLE (-1975 3750);
FORCEPROP 2 LAST BOM_COST PROC_SIDEBAND
J 0
(-1975 3750);
PAINT MONO (-1975 3750);
DISPLAY INVISIBLE (-1975 3750);
FORCEPROP 2 LAST SEC_TYPE 0402
J 0
(-2025 3975);
DISPLAY 1.021277 (-2025 3975);
PAINT ORANGE (-2025 3975);
DISPLAY INVISIBLE (-2025 3975);
FORCEPROP 2 LAST SEC 1
J 0
(-2025 3975);
DISPLAY 0.680851 (-2025 3975);
PAINT MONO (-2025 3975);
DISPLAY INVISIBLE (-2025 3975);
FORCEPROP 2 LAST CDS_LOCATION R6N10
J 0
(-2450 3750);
DISPLAY 0.617021 (-2450 3750);
PAINT AQUA (-2450 3750);
DISPLAY INVISIBLE (-2450 3750);
FORCEPROP 1 LAST PATH I149
J 0
(-2025 3900);
DISPLAY 1.319149 (-2025 3900);
PAINT WHITE (-2025 3900);
DISPLAY INVISIBLE (-2025 3900);
FORCEPROP 2 LAST ROOM CPU0
J 0
(-2025 3900);
PAINT PEACH (-2025 3900);
DISPLAY INVISIBLE (-2025 3900);
FORCEADD OFFPAGE..5
(-6350 3500);
FORCEPROP 2 LAST $XR0 98 
J 0
(-6574 3500);
DISPLAY 0.638298 (-6574 3500);
PAINT MONO (-6574 3500);
FORCEPROP 2 LAST CDS_LIB mstr_standard
J 0
(-6350 3500);
PAINT MONO (-6350 3500);
DISPLAY INVISIBLE (-6350 3500);
FORCEPROP 2 LAST PATH I15
J 0
(-6300 3575);
DISPLAY 1.361702 (-6300 3575);
PAINT ORANGE (-6300 3575);
DISPLAY INVISIBLE (-6300 3575);
FORCEPROP 1 LAST OFFPAGE TRUE
J 0
(-6025 3375);
DISPLAY 1.170213 (-6025 3375);
PAINT GREEN (-6025 3375);
DISPLAY INVISIBLE (-6025 3375);
FORCEPROP 1 LAST COMMENT_BODY TRUE
J 0
(-6250 3425);
DISPLAY 1.170213 (-6250 3425);
PAINT PEACH (-6250 3425);
DISPLAY INVISIBLE (-6250 3425);
FORCEADD RES..1
(-1975 3800);
FORCEPROP 1 LAST LOCATION R6N12
J 0
(-2450 3800);
DISPLAY 0.617021 (-2450 3800);
PAINT AQUA (-2450 3800);
FORCEPROP 1 LAST PART_NUMBER G21497-005
J 0
(-2325 3800);
DISPLAY 0.617021 (-2325 3800);
PAINT BLUE (-2325 3800);
FORCEPROP 1 LAST VALUE 0.0
J 2
(-1800 3775);
DISPLAY 0.617021 (-1800 3775);
PAINT SKYBLUE (-1800 3775);
FORCEPROP 1 LAST TOLERANCE 5%
J 0
(-1775 3775);
DISPLAY 0.617021 (-1775 3775);
PAINT SKYBLUE (-1775 3775);
FORCEPROP 1 LAST PACK_TYPE 0402
J 0
(-1675 3775);
DISPLAY 0.617021 (-1675 3775);
PAINT SKYBLUE (-1675 3775);
FORCEPROP 1 LASTPIN (-1875 3800) $PN 2
J 0
(-1913 3812);
DISPLAY 0.617021 (-1913 3812);
PAINT WHITE (-1913 3812);
FORCEPROP 1 LASTPIN (-2075 3800) $PN 1
J 0
(-2063 3812);
DISPLAY 0.617021 (-2063 3812);
PAINT WHITE (-2063 3812);
FORCEPROP 1 LAST MATERIAL CHIP
J 0
(-1825 3700);
DISPLAY 0.510638 (-1825 3700);
PAINT SKYBLUE (-1825 3700);
DISPLAY INVISIBLE (-1825 3700);
FORCEPROP 1 LAST WATTAGE 1/16W
J 2
(-1450 3775);
DISPLAY 0.510638 (-1450 3775);
PAINT SKYBLUE (-1450 3775);
DISPLAY INVISIBLE (-1450 3775);
FORCEPROP 2 LAST CDS_LIB mstr_discrete
J 0
(-1975 3800);
DISPLAY 1.340426 (-1975 3800);
PAINT ORANGE (-1975 3800);
DISPLAY INVISIBLE (-1975 3800);
FORCEPROP 2 LAST BOM_COST PROC_SIDEBAND
J 0
(-1975 3800);
PAINT MONO (-1975 3800);
DISPLAY INVISIBLE (-1975 3800);
FORCEPROP 2 LAST SEC_TYPE 0402
J 0
(-2025 4025);
DISPLAY 1.021277 (-2025 4025);
PAINT ORANGE (-2025 4025);
DISPLAY INVISIBLE (-2025 4025);
FORCEPROP 2 LAST SEC 1
J 0
(-2025 4025);
DISPLAY 0.680851 (-2025 4025);
PAINT MONO (-2025 4025);
DISPLAY INVISIBLE (-2025 4025);
FORCEPROP 2 LAST CDS_LOCATION R6N12
J 0
(-2450 3800);
DISPLAY 0.617021 (-2450 3800);
PAINT AQUA (-2450 3800);
DISPLAY INVISIBLE (-2450 3800);
FORCEPROP 1 LAST PATH I150
J 0
(-2025 3950);
DISPLAY 1.319149 (-2025 3950);
PAINT WHITE (-2025 3950);
DISPLAY INVISIBLE (-2025 3950);
FORCEPROP 2 LAST ROOM CPU0
J 0
(-2025 3950);
PAINT PEACH (-2025 3950);
DISPLAY INVISIBLE (-2025 3950);
FORCEADD RES..1
(-1975 3850);
FORCEPROP 1 LAST LOCATION R6N11
J 0
(-2450 3850);
DISPLAY 0.617021 (-2450 3850);
PAINT AQUA (-2450 3850);
FORCEPROP 1 LAST PART_NUMBER G21497-005
J 0
(-2325 3850);
DISPLAY 0.617021 (-2325 3850);
PAINT BLUE (-2325 3850);
FORCEPROP 1 LAST VALUE 0.0
J 2
(-1800 3825);
DISPLAY 0.617021 (-1800 3825);
PAINT SKYBLUE (-1800 3825);
FORCEPROP 1 LAST TOLERANCE 5%
J 0
(-1775 3825);
DISPLAY 0.617021 (-1775 3825);
PAINT SKYBLUE (-1775 3825);
FORCEPROP 1 LAST PACK_TYPE 0402
J 0
(-1675 3825);
DISPLAY 0.617021 (-1675 3825);
PAINT SKYBLUE (-1675 3825);
FORCEPROP 1 LASTPIN (-1875 3850) $PN 2
J 0
(-1913 3862);
DISPLAY 0.617021 (-1913 3862);
PAINT WHITE (-1913 3862);
FORCEPROP 1 LASTPIN (-2075 3850) $PN 1
J 0
(-2063 3862);
DISPLAY 0.617021 (-2063 3862);
PAINT WHITE (-2063 3862);
FORCEPROP 1 LAST MATERIAL CHIP
J 0
(-1825 3750);
DISPLAY 0.510638 (-1825 3750);
PAINT SKYBLUE (-1825 3750);
DISPLAY INVISIBLE (-1825 3750);
FORCEPROP 1 LAST WATTAGE 1/16W
J 2
(-1450 3825);
DISPLAY 0.510638 (-1450 3825);
PAINT SKYBLUE (-1450 3825);
DISPLAY INVISIBLE (-1450 3825);
FORCEPROP 2 LAST CDS_LIB mstr_discrete
J 0
(-1975 3850);
DISPLAY 1.340426 (-1975 3850);
PAINT ORANGE (-1975 3850);
DISPLAY INVISIBLE (-1975 3850);
FORCEPROP 2 LAST BOM_COST PROC_SIDEBAND
J 0
(-1975 3850);
PAINT MONO (-1975 3850);
DISPLAY INVISIBLE (-1975 3850);
FORCEPROP 2 LAST SEC_TYPE 0402
J 0
(-2025 4075);
DISPLAY 1.021277 (-2025 4075);
PAINT ORANGE (-2025 4075);
DISPLAY INVISIBLE (-2025 4075);
FORCEPROP 2 LAST SEC 1
J 0
(-2025 4075);
DISPLAY 0.680851 (-2025 4075);
PAINT MONO (-2025 4075);
DISPLAY INVISIBLE (-2025 4075);
FORCEPROP 2 LAST CDS_LOCATION R6N11
J 0
(-2450 3850);
DISPLAY 0.617021 (-2450 3850);
PAINT AQUA (-2450 3850);
DISPLAY INVISIBLE (-2450 3850);
FORCEPROP 1 LAST PATH I151
J 0
(-2025 4000);
DISPLAY 1.319149 (-2025 4000);
PAINT WHITE (-2025 4000);
DISPLAY INVISIBLE (-2025 4000);
FORCEPROP 2 LAST ROOM CPU0
J 0
(-2025 4000);
PAINT PEACH (-2025 4000);
DISPLAY INVISIBLE (-2025 4000);
FORCEADD RES..1
(-1975 3900);
FORCEPROP 1 LAST LOCATION R6B3
J 0
(-2450 3900);
DISPLAY 0.617021 (-2450 3900);
PAINT AQUA (-2450 3900);
FORCEPROP 1 LAST PART_NUMBER G21796-271
J 0
(-2325 3900);
DISPLAY 0.617021 (-2325 3900);
PAINT BLUE (-2325 3900);
FORCEPROP 1 LAST VALUE 221
J 2
(-1775 3875);
DISPLAY 0.617021 (-1775 3875);
PAINT SKYBLUE (-1775 3875);
FORCEPROP 1 LAST TOLERANCE 1.0%
J 0
(-1775 3875);
DISPLAY 0.617021 (-1775 3875);
PAINT SKYBLUE (-1775 3875);
FORCEPROP 1 LAST PACK_TYPE 0402
J 0
(-1675 3875);
DISPLAY 0.617021 (-1675 3875);
PAINT SKYBLUE (-1675 3875);
FORCEPROP 1 LASTPIN (-1875 3900) $PN 2
J 0
(-1913 3912);
DISPLAY 0.617021 (-1913 3912);
PAINT WHITE (-1913 3912);
FORCEPROP 1 LASTPIN (-2075 3900) $PN 1
J 0
(-2063 3912);
DISPLAY 0.617021 (-2063 3912);
PAINT WHITE (-2063 3912);
FORCEPROP 1 LAST MATERIAL CHIP
J 0
(-1825 3800);
DISPLAY 0.510638 (-1825 3800);
PAINT SKYBLUE (-1825 3800);
DISPLAY INVISIBLE (-1825 3800);
FORCEPROP 1 LAST WATTAGE 1/16W
J 2
(-1450 3875);
DISPLAY 0.510638 (-1450 3875);
PAINT SKYBLUE (-1450 3875);
DISPLAY INVISIBLE (-1450 3875);
FORCEPROP 2 LAST SEC_TYPE 0402
J 0
(-2025 4125);
DISPLAY 1.021277 (-2025 4125);
PAINT ORANGE (-2025 4125);
DISPLAY INVISIBLE (-2025 4125);
FORCEPROP 2 LAST BOM_COST PROC_SIDEBAND
J 0
(-1975 3900);
PAINT MONO (-1975 3900);
DISPLAY INVISIBLE (-1975 3900);
FORCEPROP 2 LAST CDS_LIB mstr_discrete
J 0
(-1975 3900);
DISPLAY 1.340426 (-1975 3900);
PAINT ORANGE (-1975 3900);
DISPLAY INVISIBLE (-1975 3900);
FORCEPROP 2 LAST SEC 1
J 0
(-2025 4125);
DISPLAY 0.680851 (-2025 4125);
PAINT MONO (-2025 4125);
DISPLAY INVISIBLE (-2025 4125);
FORCEPROP 2 LAST CDS_LOCATION R6B3
J 0
(-2450 3900);
DISPLAY 0.617021 (-2450 3900);
PAINT AQUA (-2450 3900);
DISPLAY INVISIBLE (-2450 3900);
FORCEPROP 1 LAST PATH I152
J 0
(-2025 4050);
DISPLAY 1.319149 (-2025 4050);
PAINT WHITE (-2025 4050);
DISPLAY INVISIBLE (-2025 4050);
FORCEPROP 2 LAST ROOM CPU0
J 0
(-2025 4050);
PAINT PEACH (-2025 4050);
DISPLAY INVISIBLE (-2025 4050);
FORCEADD RES..1
(-1975 3950);
FORCEPROP 1 LAST LOCATION R6B5
J 0
(-2450 3950);
DISPLAY 0.617021 (-2450 3950);
PAINT AQUA (-2450 3950);
FORCEPROP 1 LAST PART_NUMBER G21497-005
J 0
(-2325 3950);
DISPLAY 0.617021 (-2325 3950);
PAINT BLUE (-2325 3950);
FORCEPROP 1 LAST VALUE 0.0
J 2
(-1800 3925);
DISPLAY 0.617021 (-1800 3925);
PAINT SKYBLUE (-1800 3925);
FORCEPROP 1 LAST TOLERANCE 5%
J 0
(-1775 3925);
DISPLAY 0.617021 (-1775 3925);
PAINT SKYBLUE (-1775 3925);
FORCEPROP 1 LAST PACK_TYPE 0402
J 0
(-1675 3925);
DISPLAY 0.617021 (-1675 3925);
PAINT SKYBLUE (-1675 3925);
FORCEPROP 1 LASTPIN (-1875 3950) $PN 2
J 0
(-1913 3962);
DISPLAY 0.617021 (-1913 3962);
PAINT WHITE (-1913 3962);
FORCEPROP 1 LASTPIN (-2075 3950) $PN 1
J 0
(-2063 3962);
DISPLAY 0.617021 (-2063 3962);
PAINT WHITE (-2063 3962);
FORCEPROP 1 LAST MATERIAL CHIP
J 0
(-1825 3850);
DISPLAY 0.510638 (-1825 3850);
PAINT SKYBLUE (-1825 3850);
DISPLAY INVISIBLE (-1825 3850);
FORCEPROP 1 LAST WATTAGE 1/16W
J 2
(-1450 3925);
DISPLAY 0.510638 (-1450 3925);
PAINT SKYBLUE (-1450 3925);
DISPLAY INVISIBLE (-1450 3925);
FORCEPROP 2 LAST BOM_COST PROC_SIDEBAND
J 0
(-1975 3950);
PAINT MONO (-1975 3950);
DISPLAY INVISIBLE (-1975 3950);
FORCEPROP 2 LAST CDS_LIB mstr_discrete
J 0
(-1975 3950);
DISPLAY 1.340426 (-1975 3950);
PAINT ORANGE (-1975 3950);
DISPLAY INVISIBLE (-1975 3950);
FORCEPROP 2 LAST SEC_TYPE 0402
J 0
(-2025 4175);
DISPLAY 1.021277 (-2025 4175);
PAINT ORANGE (-2025 4175);
DISPLAY INVISIBLE (-2025 4175);
FORCEPROP 2 LAST SEC 1
J 0
(-2025 4175);
DISPLAY 0.680851 (-2025 4175);
PAINT MONO (-2025 4175);
DISPLAY INVISIBLE (-2025 4175);
FORCEPROP 2 LAST CDS_LOCATION R6B5
J 0
(-2450 3950);
DISPLAY 0.617021 (-2450 3950);
PAINT AQUA (-2450 3950);
DISPLAY INVISIBLE (-2450 3950);
FORCEPROP 1 LAST PATH I153
J 0
(-2025 4100);
DISPLAY 1.319149 (-2025 4100);
PAINT WHITE (-2025 4100);
DISPLAY INVISIBLE (-2025 4100);
FORCEPROP 2 LAST ROOM CPU0
J 0
(-2025 4100);
PAINT PEACH (-2025 4100);
DISPLAY INVISIBLE (-2025 4100);
FORCEADD RES..1
(-1975 4000);
FORCEPROP 1 LAST LOCATION R6B4
J 0
(-2450 4000);
DISPLAY 0.617021 (-2450 4000);
PAINT AQUA (-2450 4000);
FORCEPROP 1 LAST PART_NUMBER G21497-005
J 0
(-2325 4000);
DISPLAY 0.617021 (-2325 4000);
PAINT BLUE (-2325 4000);
FORCEPROP 1 LAST VALUE 0.0
J 2
(-1800 3975);
DISPLAY 0.617021 (-1800 3975);
PAINT SKYBLUE (-1800 3975);
FORCEPROP 1 LAST TOLERANCE 5%
J 0
(-1775 3975);
DISPLAY 0.617021 (-1775 3975);
PAINT SKYBLUE (-1775 3975);
FORCEPROP 1 LAST PACK_TYPE 0402
J 0
(-1675 3975);
DISPLAY 0.617021 (-1675 3975);
PAINT SKYBLUE (-1675 3975);
FORCEPROP 1 LASTPIN (-1875 4000) $PN 2
J 0
(-1913 4012);
DISPLAY 0.617021 (-1913 4012);
PAINT WHITE (-1913 4012);
FORCEPROP 1 LASTPIN (-2075 4000) $PN 1
J 0
(-2063 4012);
DISPLAY 0.617021 (-2063 4012);
PAINT WHITE (-2063 4012);
FORCEPROP 1 LAST MATERIAL CHIP
J 0
(-1825 3900);
DISPLAY 0.510638 (-1825 3900);
PAINT SKYBLUE (-1825 3900);
DISPLAY INVISIBLE (-1825 3900);
FORCEPROP 1 LAST WATTAGE 1/16W
J 2
(-1450 3975);
DISPLAY 0.510638 (-1450 3975);
PAINT SKYBLUE (-1450 3975);
DISPLAY INVISIBLE (-1450 3975);
FORCEPROP 2 LAST BOM_COST PROC_SIDEBAND
J 0
(-1975 4000);
PAINT MONO (-1975 4000);
DISPLAY INVISIBLE (-1975 4000);
FORCEPROP 2 LAST CDS_LIB mstr_discrete
J 0
(-1975 4000);
DISPLAY 1.340426 (-1975 4000);
PAINT ORANGE (-1975 4000);
DISPLAY INVISIBLE (-1975 4000);
FORCEPROP 2 LAST SEC_TYPE 0402
J 0
(-2025 4225);
DISPLAY 1.021277 (-2025 4225);
PAINT ORANGE (-2025 4225);
DISPLAY INVISIBLE (-2025 4225);
FORCEPROP 2 LAST SEC 1
J 0
(-2025 4225);
DISPLAY 0.680851 (-2025 4225);
PAINT MONO (-2025 4225);
DISPLAY INVISIBLE (-2025 4225);
FORCEPROP 2 LAST CDS_LOCATION R6B4
J 0
(-2450 4000);
DISPLAY 0.617021 (-2450 4000);
PAINT AQUA (-2450 4000);
DISPLAY INVISIBLE (-2450 4000);
FORCEPROP 1 LAST PATH I154
J 0
(-2025 4150);
DISPLAY 1.319149 (-2025 4150);
PAINT WHITE (-2025 4150);
DISPLAY INVISIBLE (-2025 4150);
FORCEPROP 2 LAST ROOM CPU0
J 0
(-2025 4150);
PAINT PEACH (-2025 4150);
DISPLAY INVISIBLE (-2025 4150);
FORCEADD OFFPAGE..3
(-775 4000);
FORCEPROP 2 LAST $XR0 194 
J 0
(-561 4000);
DISPLAY 0.638298 (-561 4000);
PAINT MONO (-561 4000);
FORCEPROP 2 LAST $XR1 215 
J 0
(-441 4000);
DISPLAY 0.638298 (-441 4000);
PAINT MONO (-441 4000);
FORCEPROP 2 LAST $XR2 218 
J 0
(-321 4000);
DISPLAY 0.638298 (-321 4000);
PAINT MONO (-321 4000);
FORCEPROP 2 LAST CDS_LIB mstr_standard
J 0
(-775 4000);
PAINT MONO (-775 4000);
DISPLAY INVISIBLE (-775 4000);
FORCEPROP 2 LAST PATH I155
J 0
(-575 4075);
DISPLAY 1.361702 (-575 4075);
PAINT ORANGE (-575 4075);
DISPLAY INVISIBLE (-575 4075);
FORCEPROP 1 LAST OFFPAGE TRUE
J 0
(-450 3875);
DISPLAY 1.170213 (-450 3875);
PAINT GREEN (-450 3875);
DISPLAY INVISIBLE (-450 3875);
FORCEPROP 1 LAST COMMENT_BODY TRUE
J 0
(-825 3900);
DISPLAY 1.170213 (-825 3900);
PAINT PEACH (-825 3900);
DISPLAY INVISIBLE (-825 3900);
FORCEADD OFFPAGE..2
(-750 3950);
FORCEPROP 2 LAST $XR0 194 
J 0
(-561 3950);
DISPLAY 0.638298 (-561 3950);
PAINT MONO (-561 3950);
FORCEPROP 2 LAST $XR1 215 
J 0
(-441 3950);
DISPLAY 0.638298 (-441 3950);
PAINT MONO (-441 3950);
FORCEPROP 2 LAST $XR2 218 
J 0
(-321 3950);
DISPLAY 0.638298 (-321 3950);
PAINT MONO (-321 3950);
FORCEPROP 2 LAST CDS_LIB mstr_standard
J 0
(-750 3950);
PAINT MONO (-750 3950);
DISPLAY INVISIBLE (-750 3950);
FORCEPROP 2 LAST PATH I156
J 0
(-575 4025);
DISPLAY 1.361702 (-575 4025);
PAINT ORANGE (-575 4025);
DISPLAY INVISIBLE (-575 4025);
FORCEPROP 1 LAST OFFPAGE TRUE
J 0
(-425 3825);
DISPLAY 1.170213 (-425 3825);
PAINT GREEN (-425 3825);
DISPLAY INVISIBLE (-425 3825);
FORCEPROP 1 LAST COMMENT_BODY TRUE
J 0
(-795 3855);
DISPLAY 1.170213 (-795 3855);
PAINT PEACH (-795 3855);
DISPLAY INVISIBLE (-795 3855);
FORCEADD OFFPAGE..4
(-750 3900);
FORCEPROP 2 LAST $XR0 194 
J 0
(-564 3900);
DISPLAY 0.638298 (-564 3900);
PAINT MONO (-564 3900);
FORCEPROP 2 LAST $XR1 215 
J 0
(-444 3900);
DISPLAY 0.638298 (-444 3900);
PAINT MONO (-444 3900);
FORCEPROP 2 LAST $XR2 218 
J 0
(-324 3900);
DISPLAY 0.638298 (-324 3900);
PAINT MONO (-324 3900);
FORCEPROP 2 LAST CDS_LIB mstr_standard
J 0
(-750 3900);
PAINT MONO (-750 3900);
DISPLAY INVISIBLE (-750 3900);
FORCEPROP 2 LAST PATH I157
J 0
(-575 3975);
DISPLAY 1.361702 (-575 3975);
PAINT ORANGE (-575 3975);
DISPLAY INVISIBLE (-575 3975);
FORCEPROP 1 LAST OFFPAGE TRUE
J 0
(-425 3775);
DISPLAY 1.170213 (-425 3775);
PAINT GREEN (-425 3775);
DISPLAY INVISIBLE (-425 3775);
FORCEPROP 1 LAST COMMENT_BODY TRUE
J 0
(-775 3800);
DISPLAY 1.170213 (-775 3800);
PAINT PEACH (-775 3800);
DISPLAY INVISIBLE (-775 3800);
FORCEADD PVCCIO_CPU0..1
(-975 4625);
FORCEPROP 3 LASTPIN (-975 4575) SIG_NAME PVCCIO_CPU0\g
J 0
(-965 4585);
DISPLAY 0.659574 (-965 4585);
PAINT MONO (-965 4585);
DISPLAY INVISIBLE (-965 4585);
FORCEPROP 1 LAST VOLTAGE 1.1V
J 0
(-1020 4582);
DISPLAY 0.340426 (-1020 4582);
PAINT SKYBLUE (-1020 4582);
DISPLAY INVISIBLE (-1020 4582);
FORCEPROP 2 LAST CDS_LIB mstr_symbols
J 0
(-975 4625);
PAINT ORANGE (-975 4625);
DISPLAY INVISIBLE (-975 4625);
FORCEPROP 1 LAST PATH I158
J 0
(-925 4650);
DISPLAY 0.872340 (-925 4650);
PAINT AQUA (-925 4650);
DISPLAY INVISIBLE (-925 4650);
FORCEPROP 1 LAST BODY_TYPE PLUMBING
J 0
(-1020 4582);
DISPLAY 0.340426 (-1020 4582);
PAINT GREEN (-1020 4582);
DISPLAY INVISIBLE (-1020 4582);
FORCEPROP 1 LAST HDL_POWER PVCCIO_CPU0
J 1
(-975 4675);
DISPLAY 0.872340 (-975 4675);
PAINT GREEN (-975 4675);
DISPLAY INVISIBLE (-975 4675);
FORCEADD RES..2
(-1200 4300);
FORCEPROP 1 LAST LOCATION R6B2
J 0
(-1155 4425);
DISPLAY 0.617021 (-1155 4425);
PAINT AQUA (-1155 4425);
FORCEPROP 1 LAST PART_NUMBER G21796-017
R 1
J 0
(-1135 4100);
DISPLAY 0.617021 (-1135 4100);
PAINT BLUE (-1135 4100);
FORCEPROP 1 LAST VALUE 100.0
R 1
J 0
(-1080 4275);
DISPLAY 0.617021 (-1080 4275);
PAINT SKYBLUE (-1080 4275);
FORCEPROP 1 LAST MATERIAL CHIP
R 1
J 0
(-1085 4100);
DISPLAY 0.617021 (-1085 4100);
PAINT SKYBLUE (-1085 4100);
FORCEPROP 1 LASTPIN (-1200 4200) $PN 2
J 0
(-1195 4210);
DISPLAY 0.617021 (-1195 4210);
PAINT WHITE (-1195 4210);
FORCEPROP 1 LASTPIN (-1200 4400) $PN 1
J 0
(-1195 4362);
DISPLAY 0.617021 (-1195 4362);
PAINT WHITE (-1195 4362);
FORCEPROP 1 LAST TOLERANCE 1%
J 0
(-1155 4325);
DISPLAY 0.510638 (-1155 4325);
PAINT SKYBLUE (-1155 4325);
DISPLAY INVISIBLE (-1155 4325);
FORCEPROP 1 LAST PACK_TYPE 0402
J 0
(-1160 4125);
DISPLAY 0.510638 (-1160 4125);
PAINT SKYBLUE (-1160 4125);
DISPLAY INVISIBLE (-1160 4125);
FORCEPROP 1 LAST WATTAGE 1/16W
J 0
(-1160 4275);
DISPLAY 0.510638 (-1160 4275);
PAINT SKYBLUE (-1160 4275);
DISPLAY INVISIBLE (-1160 4275);
FORCEPROP 2 LAST BOM_COST PROC_SIDEBAND
J 0
(-1200 4300);
PAINT MONO (-1200 4300);
DISPLAY INVISIBLE (-1200 4300);
FORCEPROP 2 LAST CDS_LIB mstr_discrete
J 0
(-1200 4300);
PAINT ORANGE (-1200 4300);
DISPLAY INVISIBLE (-1200 4300);
FORCEPROP 2 LAST SEC_TYPE 0402
J 0
(-1150 4550);
DISPLAY 1.021277 (-1150 4550);
PAINT ORANGE (-1150 4550);
DISPLAY INVISIBLE (-1150 4550);
FORCEPROP 2 LAST SEC 1
J 0
(-1150 4550);
DISPLAY 0.680851 (-1150 4550);
PAINT MONO (-1150 4550);
DISPLAY INVISIBLE (-1150 4550);
FORCEPROP 2 LAST CDS_LOCATION R6B2
J 0
(-1155 4425);
DISPLAY 0.617021 (-1155 4425);
PAINT AQUA (-1155 4425);
DISPLAY INVISIBLE (-1155 4425);
FORCEPROP 1 LAST PATH I159
J 0
(-1150 4475);
DISPLAY 1.319149 (-1150 4475);
PAINT WHITE (-1150 4475);
DISPLAY INVISIBLE (-1150 4475);
FORCEPROP 2 LAST ROOM CPU0
J 0
(-1175 4075);
PAINT ORANGE (-1175 4075);
DISPLAY INVISIBLE (-1175 4075);
FORCEADD RES..2
(-975 4300);
FORCEPROP 1 LAST LOCATION R6B1
J 0
(-930 4425);
DISPLAY 0.617021 (-930 4425);
PAINT AQUA (-930 4425);
FORCEPROP 1 LAST PART_NUMBER G21796-047
R 1
J 0
(-910 4100);
DISPLAY 0.617021 (-910 4100);
PAINT BLUE (-910 4100);
FORCEPROP 1 LAST VALUE 49.9
R 1
J 0
(-855 4275);
DISPLAY 0.617021 (-855 4275);
PAINT SKYBLUE (-855 4275);
FORCEPROP 1 LAST MATERIAL CHIP
R 1
J 0
(-860 4100);
DISPLAY 0.617021 (-860 4100);
PAINT SKYBLUE (-860 4100);
FORCEPROP 1 LASTPIN (-975 4200) $PN 2
J 0
(-970 4210);
DISPLAY 0.617021 (-970 4210);
PAINT WHITE (-970 4210);
FORCEPROP 1 LASTPIN (-975 4400) $PN 1
J 0
(-970 4362);
DISPLAY 0.617021 (-970 4362);
PAINT WHITE (-970 4362);
FORCEPROP 1 LAST TOLERANCE 1%
J 0
(-930 4325);
DISPLAY 0.510638 (-930 4325);
PAINT SKYBLUE (-930 4325);
DISPLAY INVISIBLE (-930 4325);
FORCEPROP 1 LAST PACK_TYPE 0402
J 0
(-935 4125);
DISPLAY 0.510638 (-935 4125);
PAINT SKYBLUE (-935 4125);
DISPLAY INVISIBLE (-935 4125);
FORCEPROP 1 LAST WATTAGE 1/16W
J 0
(-935 4275);
DISPLAY 0.510638 (-935 4275);
PAINT SKYBLUE (-935 4275);
DISPLAY INVISIBLE (-935 4275);
FORCEPROP 2 LAST SEC_TYPE 0402
J 0
(-925 4550);
DISPLAY 1.021277 (-925 4550);
PAINT ORANGE (-925 4550);
DISPLAY INVISIBLE (-925 4550);
FORCEPROP 2 LAST BOM_COST PROC_SIDEBAND
J 0
(-975 4300);
PAINT MONO (-975 4300);
DISPLAY INVISIBLE (-975 4300);
FORCEPROP 2 LAST CDS_LIB mstr_discrete
J 0
(-975 4300);
PAINT ORANGE (-975 4300);
DISPLAY INVISIBLE (-975 4300);
FORCEPROP 2 LAST SEC 1
J 0
(-925 4550);
DISPLAY 0.680851 (-925 4550);
PAINT MONO (-925 4550);
DISPLAY INVISIBLE (-925 4550);
FORCEPROP 2 LAST CDS_LOCATION R6B1
J 0
(-930 4425);
DISPLAY 0.617021 (-930 4425);
PAINT AQUA (-930 4425);
DISPLAY INVISIBLE (-930 4425);
FORCEPROP 1 LAST PATH I161
J 0
(-925 4475);
DISPLAY 1.319149 (-925 4475);
PAINT WHITE (-925 4475);
DISPLAY INVISIBLE (-925 4475);
FORCEPROP 2 LAST ROOM CPU0
J 0
(-950 4075);
PAINT ORANGE (-950 4075);
DISPLAY INVISIBLE (-950 4075);
FORCEADD RES..2
(-1200 3475);
FORCEPROP 1 LAST LOCATION R6N2
J 0
(-1155 3600);
DISPLAY 0.617021 (-1155 3600);
PAINT AQUA (-1155 3600);
FORCEPROP 1 LAST PART_NUMBER G21796-017
R 1
J 0
(-1135 3275);
DISPLAY 0.617021 (-1135 3275);
PAINT BLUE (-1135 3275);
FORCEPROP 1 LAST VALUE 100.0
R 1
J 0
(-1080 3450);
DISPLAY 0.617021 (-1080 3450);
PAINT SKYBLUE (-1080 3450);
FORCEPROP 1 LAST MATERIAL CHIP
R 1
J 0
(-1085 3275);
DISPLAY 0.617021 (-1085 3275);
PAINT SKYBLUE (-1085 3275);
FORCEPROP 1 LASTPIN (-1200 3375) $PN 2
J 0
(-1195 3385);
DISPLAY 0.617021 (-1195 3385);
PAINT WHITE (-1195 3385);
FORCEPROP 1 LASTPIN (-1200 3575) $PN 1
J 0
(-1195 3537);
DISPLAY 0.617021 (-1195 3537);
PAINT WHITE (-1195 3537);
FORCEPROP 1 LAST TOLERANCE 1%
J 0
(-1155 3500);
DISPLAY 0.510638 (-1155 3500);
PAINT SKYBLUE (-1155 3500);
DISPLAY INVISIBLE (-1155 3500);
FORCEPROP 1 LAST PACK_TYPE 0402
J 0
(-1160 3300);
DISPLAY 0.510638 (-1160 3300);
PAINT SKYBLUE (-1160 3300);
DISPLAY INVISIBLE (-1160 3300);
FORCEPROP 1 LAST WATTAGE 1/16W
J 0
(-1160 3450);
DISPLAY 0.510638 (-1160 3450);
PAINT SKYBLUE (-1160 3450);
DISPLAY INVISIBLE (-1160 3450);
FORCEPROP 2 LAST BOM_COST PROC_SIDEBAND
J 0
(-1200 3475);
PAINT MONO (-1200 3475);
DISPLAY INVISIBLE (-1200 3475);
FORCEPROP 2 LAST CDS_LIB mstr_discrete
J 0
(-1200 3475);
PAINT ORANGE (-1200 3475);
DISPLAY INVISIBLE (-1200 3475);
FORCEPROP 2 LAST SEC_TYPE 0402
J 0
(-1150 3725);
DISPLAY 1.021277 (-1150 3725);
PAINT ORANGE (-1150 3725);
DISPLAY INVISIBLE (-1150 3725);
FORCEPROP 2 LAST SEC 1
J 0
(-1150 3725);
DISPLAY 0.680851 (-1150 3725);
PAINT MONO (-1150 3725);
DISPLAY INVISIBLE (-1150 3725);
FORCEPROP 2 LAST CDS_LOCATION R6N2
J 0
(-1155 3600);
DISPLAY 0.617021 (-1155 3600);
PAINT AQUA (-1155 3600);
DISPLAY INVISIBLE (-1155 3600);
FORCEPROP 1 LAST PATH I163
J 0
(-1150 3650);
DISPLAY 1.319149 (-1150 3650);
PAINT WHITE (-1150 3650);
DISPLAY INVISIBLE (-1150 3650);
FORCEPROP 2 LAST ROOM CPU0
J 0
(-1175 3250);
PAINT ORANGE (-1175 3250);
DISPLAY INVISIBLE (-1175 3250);
FORCEADD RES..2
(-975 3500);
FORCEPROP 1 LAST LOCATION R6N1
J 0
(-930 3600);
DISPLAY 0.617021 (-930 3600);
PAINT AQUA (-930 3600);
FORCEPROP 1 LAST PART_NUMBER G21796-047
R 1
J 0
(-910 3300);
DISPLAY 0.617021 (-910 3300);
PAINT BLUE (-910 3300);
FORCEPROP 1 LAST VALUE 49.9
R 1
J 0
(-855 3475);
DISPLAY 0.617021 (-855 3475);
PAINT SKYBLUE (-855 3475);
FORCEPROP 1 LAST MATERIAL CHIP
R 1
J 0
(-860 3300);
DISPLAY 0.617021 (-860 3300);
PAINT SKYBLUE (-860 3300);
FORCEPROP 1 LASTPIN (-975 3400) $PN 2
J 0
(-970 3410);
DISPLAY 0.617021 (-970 3410);
PAINT WHITE (-970 3410);
FORCEPROP 1 LASTPIN (-975 3600) $PN 1
J 0
(-970 3562);
DISPLAY 0.617021 (-970 3562);
PAINT WHITE (-970 3562);
FORCEPROP 1 LAST TOLERANCE 1%
J 0
(-930 3525);
DISPLAY 0.510638 (-930 3525);
PAINT SKYBLUE (-930 3525);
DISPLAY INVISIBLE (-930 3525);
FORCEPROP 1 LAST PACK_TYPE 0402
J 0
(-935 3325);
DISPLAY 0.510638 (-935 3325);
PAINT SKYBLUE (-935 3325);
DISPLAY INVISIBLE (-935 3325);
FORCEPROP 1 LAST WATTAGE 1/16W
J 0
(-935 3475);
DISPLAY 0.510638 (-935 3475);
PAINT SKYBLUE (-935 3475);
DISPLAY INVISIBLE (-935 3475);
FORCEPROP 2 LAST SEC_TYPE 0402
J 0
(-925 3750);
DISPLAY 1.021277 (-925 3750);
PAINT ORANGE (-925 3750);
DISPLAY INVISIBLE (-925 3750);
FORCEPROP 2 LAST CDS_LIB mstr_discrete
J 0
(-975 3500);
PAINT ORANGE (-975 3500);
DISPLAY INVISIBLE (-975 3500);
FORCEPROP 2 LAST BOM_COST PROC_SIDEBAND
J 0
(-975 3500);
PAINT MONO (-975 3500);
DISPLAY INVISIBLE (-975 3500);
FORCEPROP 2 LAST SEC 1
J 0
(-925 3750);
DISPLAY 0.680851 (-925 3750);
PAINT MONO (-925 3750);
DISPLAY INVISIBLE (-925 3750);
FORCEPROP 2 LAST CDS_LOCATION R6N1
J 0
(-930 3600);
DISPLAY 0.617021 (-930 3600);
PAINT AQUA (-930 3600);
DISPLAY INVISIBLE (-930 3600);
FORCEPROP 1 LAST PATH I164
J 0
(-925 3675);
DISPLAY 1.319149 (-925 3675);
PAINT WHITE (-925 3675);
DISPLAY INVISIBLE (-925 3675);
FORCEPROP 2 LAST ROOM CPU0
J 0
(-950 3275);
PAINT ORANGE (-950 3275);
DISPLAY INVISIBLE (-950 3275);
FORCEADD OFFPAGE..1
(-6350 4200);
FORCEPROP 2 LAST $XR0 103 
J 0
(-6602 4200);
DISPLAY 0.638298 (-6602 4200);
PAINT MONO (-6602 4200);
FORCEPROP 2 LAST CDS_LIB mstr_standard
J 0
(-6350 4200);
PAINT MONO (-6350 4200);
DISPLAY INVISIBLE (-6350 4200);
FORCEPROP 2 LAST PATH I169
J 0
(-6300 4275);
DISPLAY 1.021277 (-6300 4275);
PAINT ORANGE (-6300 4275);
DISPLAY INVISIBLE (-6300 4275);
FORCEPROP 1 LAST OFFPAGE TRUE
J 0
(-6025 4075);
DISPLAY 1.170213 (-6025 4075);
PAINT GREEN (-6025 4075);
DISPLAY INVISIBLE (-6025 4075);
FORCEPROP 1 LAST COMMENT_BODY TRUE
J 0
(-6225 4100);
DISPLAY 1.170213 (-6225 4100);
PAINT PEACH (-6225 4100);
DISPLAY INVISIBLE (-6225 4100);
FORCEADD OFFPAGE..1
(-6350 4150);
FORCEPROP 2 LAST $XR0 103 
J 0
(-6602 4150);
DISPLAY 0.638298 (-6602 4150);
PAINT MONO (-6602 4150);
FORCEPROP 2 LAST CDS_LIB mstr_standard
J 0
(-6350 4150);
PAINT MONO (-6350 4150);
DISPLAY INVISIBLE (-6350 4150);
FORCEPROP 2 LAST PATH I170
J 0
(-6300 4225);
DISPLAY 1.021277 (-6300 4225);
PAINT ORANGE (-6300 4225);
DISPLAY INVISIBLE (-6300 4225);
FORCEPROP 1 LAST OFFPAGE TRUE
J 0
(-6025 4025);
DISPLAY 1.170213 (-6025 4025);
PAINT GREEN (-6025 4025);
DISPLAY INVISIBLE (-6025 4025);
FORCEPROP 1 LAST COMMENT_BODY TRUE
J 0
(-6225 4050);
DISPLAY 1.170213 (-6225 4050);
PAINT PEACH (-6225 4050);
DISPLAY INVISIBLE (-6225 4050);
FORCEADD OFFPAGE..3
R 2
(-6375 1800);
FORCEPROP 2 LAST $XR0 55 
J 0
(-6624 1800);
DISPLAY 0.638298 (-6624 1800);
PAINT MONO (-6624 1800);
FORCEPROP 2 LAST $XR1 112 
J 0
(-6744 1800);
DISPLAY 0.638298 (-6744 1800);
PAINT MONO (-6744 1800);
FORCEPROP 2 LAST CDS_LIB mstr_standard
J 2
(-6375 1800);
PAINT MONO (-6375 1800);
DISPLAY INVISIBLE (-6375 1800);
FORCEPROP 2 LAST PATH I172
J 2
(-6425 1875);
DISPLAY 1.021277 (-6425 1875);
PAINT ORANGE (-6425 1875);
DISPLAY INVISIBLE (-6425 1875);
FORCEPROP 1 LAST OFFPAGE TRUE
J 2
(-6700 1675);
DISPLAY 0.872340 (-6700 1675);
PAINT GREEN (-6700 1675);
DISPLAY INVISIBLE (-6700 1675);
FORCEPROP 1 LAST COMMENT_BODY TRUE
J 2
(-6325 1700);
DISPLAY 0.872340 (-6325 1700);
PAINT GREEN (-6325 1700);
DISPLAY INVISIBLE (-6325 1700);
FORCEADD OFFPAGE..4
(-1825 4200);
FORCEPROP 2 LAST $XR0 114 
J 0
(-1639 4200);
DISPLAY 0.638298 (-1639 4200);
PAINT MONO (-1639 4200);
FORCEPROP 2 LAST $XR1 55 
J 0
(-1519 4200);
DISPLAY 0.638298 (-1519 4200);
PAINT MONO (-1519 4200);
FORCEPROP 2 LAST CDS_LIB mstr_standard
J 0
(-1825 4200);
PAINT ORANGE (-1825 4200);
DISPLAY INVISIBLE (-1825 4200);
FORCEPROP 2 LAST PATH I175
J 0
(-1650 4275);
DISPLAY 1.021277 (-1650 4275);
PAINT ORANGE (-1650 4275);
DISPLAY INVISIBLE (-1650 4275);
FORCEPROP 1 LAST OFFPAGE TRUE
J 0
(-1500 4075);
DISPLAY 1.170213 (-1500 4075);
PAINT GREEN (-1500 4075);
DISPLAY INVISIBLE (-1500 4075);
FORCEPROP 1 LAST COMMENT_BODY TRUE
J 0
(-1850 4100);
DISPLAY 1.170213 (-1850 4100);
PAINT PEACH (-1850 4100);
DISPLAY INVISIBLE (-1850 4100);
FORCEADD RES..2
R 2
(-6625 2875);
FORCEPROP 1 LAST LOCATION R5D1
J 2
(-6670 3000);
DISPLAY 0.617021 (-6670 3000);
PAINT AQUA (-6670 3000);
FORCEPROP 1 LAST PART_NUMBER G21796-365
J 2
(-6665 2750);
DISPLAY 0.617021 (-6665 2750);
PAINT BLUE (-6665 2750);
FORCEPROP 1 LAST VALUE 90.9
J 2
(-6670 2950);
DISPLAY 0.617021 (-6670 2950);
PAINT SKYBLUE (-6670 2950);
FORCEPROP 1 LAST TOLERANCE 1%
J 2
(-6670 2900);
DISPLAY 0.617021 (-6670 2900);
PAINT SKYBLUE (-6670 2900);
FORCEPROP 1 LAST PACK_TYPE 0402
J 2
(-6665 2700);
DISPLAY 0.617021 (-6665 2700);
PAINT SKYBLUE (-6665 2700);
FORCEPROP 1 LAST MATERIAL CHIP
J 2
(-6665 2800);
DISPLAY 0.617021 (-6665 2800);
PAINT SKYBLUE (-6665 2800);
FORCEPROP 1 LAST WATTAGE 1/16W
J 2
(-6665 2850);
DISPLAY 0.617021 (-6665 2850);
PAINT SKYBLUE (-6665 2850);
FORCEPROP 1 LASTPIN (-6625 2775) $PN 2
J 2
(-6630 2785);
DISPLAY 0.617021 (-6630 2785);
PAINT ORANGE (-6630 2785);
FORCEPROP 1 LASTPIN (-6625 2975) $PN 1
J 2
(-6630 2937);
DISPLAY 0.617021 (-6630 2937);
PAINT ORANGE (-6630 2937);
FORCEPROP 2 LAST SEC_TYPE 0402
J 0
(-6675 3100);
DISPLAY 1.021277 (-6675 3100);
PAINT ORANGE (-6675 3100);
DISPLAY INVISIBLE (-6675 3100);
FORCEPROP 2 LAST CDS_LIB mstr_discrete
J 0
(-6625 2875);
PAINT ORANGE (-6625 2875);
DISPLAY INVISIBLE (-6625 2875);
FORCEPROP 0 LAST BOM_COST PROC_SOCKET
J 0
(-6650 3100);
DISPLAY 1.021277 (-6650 3100);
PAINT ORANGE (-6650 3100);
DISPLAY INVISIBLE (-6650 3100);
FORCEPROP 2 LAST SEC 1
J 0
(-6675 3100);
DISPLAY 0.680851 (-6675 3100);
PAINT MONO (-6675 3100);
DISPLAY INVISIBLE (-6675 3100);
FORCEPROP 2 LAST CDS_LOCATION R5D1
J 2
(-6670 3000);
DISPLAY 0.617021 (-6670 3000);
PAINT AQUA (-6670 3000);
DISPLAY INVISIBLE (-6670 3000);
FORCEPROP 1 LAST PATH I177
J 2
(-6675 3050);
DISPLAY 0.978723 (-6675 3050);
PAINT WHITE (-6675 3050);
DISPLAY INVISIBLE (-6675 3050);
FORCEPROP 0 LAST ROOM CPU0
J 0
(-6650 3100);
DISPLAY 1.021277 (-6650 3100);
PAINT ORANGE (-6650 3100);
DISPLAY INVISIBLE (-6650 3100);
FORCEADD RES..2
R 2
(-6875 2925);
FORCEPROP 1 LAST LOCATION R5D2
J 2
(-6920 3050);
DISPLAY 0.617021 (-6920 3050);
PAINT AQUA (-6920 3050);
FORCEPROP 1 LAST PART_NUMBER G21796-365
J 2
(-6915 2800);
DISPLAY 0.617021 (-6915 2800);
PAINT BLUE (-6915 2800);
FORCEPROP 1 LAST VALUE 90.9
J 2
(-6920 3000);
DISPLAY 0.617021 (-6920 3000);
PAINT SKYBLUE (-6920 3000);
FORCEPROP 1 LAST TOLERANCE 1%
J 2
(-6920 2950);
DISPLAY 0.617021 (-6920 2950);
PAINT SKYBLUE (-6920 2950);
FORCEPROP 1 LAST PACK_TYPE 0402
J 2
(-6915 2750);
DISPLAY 0.617021 (-6915 2750);
PAINT SKYBLUE (-6915 2750);
FORCEPROP 1 LAST MATERIAL CHIP
J 2
(-6915 2850);
DISPLAY 0.617021 (-6915 2850);
PAINT SKYBLUE (-6915 2850);
FORCEPROP 1 LAST WATTAGE 1/16W
J 2
(-6915 2900);
DISPLAY 0.617021 (-6915 2900);
PAINT SKYBLUE (-6915 2900);
FORCEPROP 1 LASTPIN (-6875 2825) $PN 2
J 2
(-6880 2835);
DISPLAY 0.617021 (-6880 2835);
PAINT ORANGE (-6880 2835);
FORCEPROP 1 LASTPIN (-6875 3025) $PN 1
J 2
(-6880 2987);
DISPLAY 0.617021 (-6880 2987);
PAINT ORANGE (-6880 2987);
FORCEPROP 2 LAST SEC_TYPE 0402
J 0
(-6925 3150);
DISPLAY 1.021277 (-6925 3150);
PAINT ORANGE (-6925 3150);
DISPLAY INVISIBLE (-6925 3150);
FORCEPROP 2 LAST CDS_LIB mstr_discrete
J 0
(-6875 2925);
PAINT ORANGE (-6875 2925);
DISPLAY INVISIBLE (-6875 2925);
FORCEPROP 0 LAST BOM_COST PROC_SOCKET
J 0
(-6900 3150);
DISPLAY 1.021277 (-6900 3150);
PAINT ORANGE (-6900 3150);
DISPLAY INVISIBLE (-6900 3150);
FORCEPROP 2 LAST SEC 1
J 0
(-6925 3150);
DISPLAY 0.680851 (-6925 3150);
PAINT MONO (-6925 3150);
DISPLAY INVISIBLE (-6925 3150);
FORCEPROP 2 LAST CDS_LOCATION R5D2
J 2
(-6920 3050);
DISPLAY 0.617021 (-6920 3050);
PAINT AQUA (-6920 3050);
DISPLAY INVISIBLE (-6920 3050);
FORCEPROP 1 LAST PATH I178
J 2
(-6925 3100);
DISPLAY 0.978723 (-6925 3100);
PAINT WHITE (-6925 3100);
DISPLAY INVISIBLE (-6925 3100);
FORCEPROP 0 LAST ROOM CPU0
J 0
(-6900 3150);
DISPLAY 1.021277 (-6900 3150);
PAINT ORANGE (-6900 3150);
DISPLAY INVISIBLE (-6900 3150);
FORCEADD RES..2
R 2
(-7125 2925);
FORCEPROP 1 LAST LOCATION R6D1
J 2
(-7170 3050);
DISPLAY 0.617021 (-7170 3050);
PAINT AQUA (-7170 3050);
FORCEPROP 1 LAST PART_NUMBER G21796-017
J 2
(-7165 2800);
DISPLAY 0.617021 (-7165 2800);
PAINT BLUE (-7165 2800);
FORCEPROP 1 LAST VALUE 100.0
J 2
(-7170 3000);
DISPLAY 0.617021 (-7170 3000);
PAINT SKYBLUE (-7170 3000);
FORCEPROP 1 LAST TOLERANCE 1%
J 2
(-7170 2950);
DISPLAY 0.617021 (-7170 2950);
PAINT SKYBLUE (-7170 2950);
FORCEPROP 1 LAST PACK_TYPE 0402
J 2
(-7165 2750);
DISPLAY 0.617021 (-7165 2750);
PAINT SKYBLUE (-7165 2750);
FORCEPROP 1 LAST MATERIAL CHIP
J 2
(-7165 2850);
DISPLAY 0.617021 (-7165 2850);
PAINT SKYBLUE (-7165 2850);
FORCEPROP 1 LAST WATTAGE 1/16W
J 2
(-7165 2900);
DISPLAY 0.617021 (-7165 2900);
PAINT SKYBLUE (-7165 2900);
FORCEPROP 1 LASTPIN (-7125 2825) $PN 2
J 2
(-7130 2835);
DISPLAY 0.617021 (-7130 2835);
PAINT ORANGE (-7130 2835);
FORCEPROP 1 LASTPIN (-7125 3025) $PN 1
J 2
(-7130 2987);
DISPLAY 0.617021 (-7130 2987);
PAINT ORANGE (-7130 2987);
FORCEPROP 2 LAST SEC_TYPE 0402
J 0
(-7175 3150);
DISPLAY 1.021277 (-7175 3150);
PAINT ORANGE (-7175 3150);
DISPLAY INVISIBLE (-7175 3150);
FORCEPROP 2 LAST CDS_LIB mstr_discrete
J 0
(-7125 2925);
PAINT ORANGE (-7125 2925);
DISPLAY INVISIBLE (-7125 2925);
FORCEPROP 0 LAST BOM_COST PROC_SOCKET
J 0
(-7150 3150);
DISPLAY 1.021277 (-7150 3150);
PAINT ORANGE (-7150 3150);
DISPLAY INVISIBLE (-7150 3150);
FORCEPROP 2 LAST SEC 1
J 0
(-7175 3150);
DISPLAY 0.680851 (-7175 3150);
PAINT MONO (-7175 3150);
DISPLAY INVISIBLE (-7175 3150);
FORCEPROP 2 LAST CDS_LOCATION R6D1
J 2
(-7170 3050);
DISPLAY 0.617021 (-7170 3050);
PAINT AQUA (-7170 3050);
DISPLAY INVISIBLE (-7170 3050);
FORCEPROP 1 LAST PATH I179
J 2
(-7175 3100);
DISPLAY 0.978723 (-7175 3100);
PAINT WHITE (-7175 3100);
DISPLAY INVISIBLE (-7175 3100);
FORCEPROP 0 LAST ROOM CPU0
J 0
(-7150 3150);
DISPLAY 1.021277 (-7150 3150);
PAINT ORANGE (-7150 3150);
DISPLAY INVISIBLE (-7150 3150);
FORCEADD OFFPAGE..5
(-6350 3350);
FORCEPROP 2 LAST $XR0 98 
J 0
(-6574 3350);
DISPLAY 0.638298 (-6574 3350);
PAINT MONO (-6574 3350);
FORCEPROP 2 LAST CDS_LIB mstr_standard
J 0
(-6350 3350);
PAINT MONO (-6350 3350);
DISPLAY INVISIBLE (-6350 3350);
FORCEPROP 2 LAST PATH I18
J 0
(-6300 3425);
DISPLAY 1.361702 (-6300 3425);
PAINT ORANGE (-6300 3425);
DISPLAY INVISIBLE (-6300 3425);
FORCEPROP 1 LAST OFFPAGE TRUE
J 0
(-6025 3225);
DISPLAY 1.170213 (-6025 3225);
PAINT GREEN (-6025 3225);
DISPLAY INVISIBLE (-6025 3225);
FORCEPROP 1 LAST COMMENT_BODY TRUE
J 0
(-6250 3275);
DISPLAY 1.170213 (-6250 3275);
PAINT PEACH (-6250 3275);
DISPLAY INVISIBLE (-6250 3275);
FORCEADD RES..2
R 2
(-7350 2925);
FORCEPROP 1 LAST LOCATION R4P8
J 2
(-7395 3050);
DISPLAY 0.617021 (-7395 3050);
PAINT AQUA (-7395 3050);
FORCEPROP 1 LAST PART_NUMBER G21796-365
J 2
(-7390 2800);
DISPLAY 0.617021 (-7390 2800);
PAINT BLUE (-7390 2800);
FORCEPROP 1 LAST VALUE 90.9
J 2
(-7395 3000);
DISPLAY 0.617021 (-7395 3000);
PAINT SKYBLUE (-7395 3000);
FORCEPROP 1 LAST TOLERANCE 1%
J 2
(-7395 2950);
DISPLAY 0.617021 (-7395 2950);
PAINT SKYBLUE (-7395 2950);
FORCEPROP 1 LAST PACK_TYPE 0402
J 2
(-7390 2750);
DISPLAY 0.617021 (-7390 2750);
PAINT SKYBLUE (-7390 2750);
FORCEPROP 1 LAST MATERIAL CHIP
J 2
(-7390 2850);
DISPLAY 0.617021 (-7390 2850);
PAINT SKYBLUE (-7390 2850);
FORCEPROP 1 LAST WATTAGE 1/16W
J 2
(-7390 2900);
DISPLAY 0.617021 (-7390 2900);
PAINT SKYBLUE (-7390 2900);
FORCEPROP 1 LASTPIN (-7350 2825) $PN 2
J 2
(-7355 2835);
DISPLAY 0.617021 (-7355 2835);
PAINT ORANGE (-7355 2835);
FORCEPROP 1 LASTPIN (-7350 3025) $PN 1
J 2
(-7355 2987);
DISPLAY 0.617021 (-7355 2987);
PAINT ORANGE (-7355 2987);
FORCEPROP 2 LAST SEC_TYPE 0402
J 0
(-7400 3150);
DISPLAY 1.021277 (-7400 3150);
PAINT ORANGE (-7400 3150);
DISPLAY INVISIBLE (-7400 3150);
FORCEPROP 2 LAST CDS_LIB mstr_discrete
J 0
(-7350 2925);
PAINT ORANGE (-7350 2925);
DISPLAY INVISIBLE (-7350 2925);
FORCEPROP 0 LAST BOM_COST PROC_SOCKET
J 0
(-7375 3150);
DISPLAY 1.021277 (-7375 3150);
PAINT ORANGE (-7375 3150);
DISPLAY INVISIBLE (-7375 3150);
FORCEPROP 2 LAST SEC 1
J 0
(-7400 3150);
DISPLAY 0.680851 (-7400 3150);
PAINT MONO (-7400 3150);
DISPLAY INVISIBLE (-7400 3150);
FORCEPROP 2 LAST CDS_LOCATION R4P8
J 2
(-7395 3050);
DISPLAY 0.617021 (-7395 3050);
PAINT AQUA (-7395 3050);
DISPLAY INVISIBLE (-7395 3050);
FORCEPROP 1 LAST PATH I180
J 2
(-7400 3100);
DISPLAY 0.978723 (-7400 3100);
PAINT WHITE (-7400 3100);
DISPLAY INVISIBLE (-7400 3100);
FORCEPROP 0 LAST ROOM CPU0
J 0
(-7375 3150);
DISPLAY 1.021277 (-7375 3150);
PAINT ORANGE (-7375 3150);
DISPLAY INVISIBLE (-7375 3150);
FORCEADD RES..2
R 2
(-7575 3000);
FORCEPROP 1 LAST LOCATION R4P10
J 2
(-7620 3125);
DISPLAY 0.617021 (-7620 3125);
PAINT AQUA (-7620 3125);
FORCEPROP 1 LAST PART_NUMBER G21796-365
J 2
(-7615 2875);
DISPLAY 0.617021 (-7615 2875);
PAINT BLUE (-7615 2875);
FORCEPROP 1 LAST VALUE 90.9
J 2
(-7620 3075);
DISPLAY 0.617021 (-7620 3075);
PAINT SKYBLUE (-7620 3075);
FORCEPROP 1 LAST TOLERANCE 1%
J 2
(-7620 3025);
DISPLAY 0.617021 (-7620 3025);
PAINT SKYBLUE (-7620 3025);
FORCEPROP 1 LAST PACK_TYPE 0402
J 2
(-7615 2825);
DISPLAY 0.617021 (-7615 2825);
PAINT SKYBLUE (-7615 2825);
FORCEPROP 1 LAST MATERIAL CHIP
J 2
(-7615 2925);
DISPLAY 0.617021 (-7615 2925);
PAINT SKYBLUE (-7615 2925);
FORCEPROP 1 LAST WATTAGE 1/16W
J 2
(-7615 2975);
DISPLAY 0.617021 (-7615 2975);
PAINT SKYBLUE (-7615 2975);
FORCEPROP 1 LASTPIN (-7575 2900) $PN 2
J 2
(-7580 2910);
DISPLAY 0.617021 (-7580 2910);
PAINT ORANGE (-7580 2910);
FORCEPROP 1 LASTPIN (-7575 3100) $PN 1
J 2
(-7580 3062);
DISPLAY 0.617021 (-7580 3062);
PAINT ORANGE (-7580 3062);
FORCEPROP 2 LAST SEC_TYPE 0402
J 0
(-7625 3225);
DISPLAY 1.021277 (-7625 3225);
PAINT ORANGE (-7625 3225);
DISPLAY INVISIBLE (-7625 3225);
FORCEPROP 2 LAST CDS_LIB mstr_discrete
J 0
(-7575 3000);
PAINT ORANGE (-7575 3000);
DISPLAY INVISIBLE (-7575 3000);
FORCEPROP 0 LAST BOM_COST PROC_SOCKET
J 0
(-7600 3225);
DISPLAY 1.021277 (-7600 3225);
PAINT ORANGE (-7600 3225);
DISPLAY INVISIBLE (-7600 3225);
FORCEPROP 2 LAST SEC 1
J 0
(-7625 3225);
DISPLAY 0.680851 (-7625 3225);
PAINT MONO (-7625 3225);
DISPLAY INVISIBLE (-7625 3225);
FORCEPROP 2 LAST CDS_LOCATION R4P10
J 2
(-7620 3125);
DISPLAY 0.617021 (-7620 3125);
PAINT AQUA (-7620 3125);
DISPLAY INVISIBLE (-7620 3125);
FORCEPROP 1 LAST PATH I181
J 2
(-7625 3175);
DISPLAY 0.978723 (-7625 3175);
PAINT WHITE (-7625 3175);
DISPLAY INVISIBLE (-7625 3175);
FORCEPROP 0 LAST ROOM CPU0
J 0
(-7600 3225);
DISPLAY 1.021277 (-7600 3225);
PAINT ORANGE (-7600 3225);
DISPLAY INVISIBLE (-7600 3225);
FORCEADD RES..2
R 2
(-7800 3000);
FORCEPROP 1 LAST LOCATION R4P11
J 2
(-7845 3125);
DISPLAY 0.617021 (-7845 3125);
PAINT AQUA (-7845 3125);
FORCEPROP 1 LAST PART_NUMBER G21796-017
J 2
(-7840 2875);
DISPLAY 0.617021 (-7840 2875);
PAINT BLUE (-7840 2875);
FORCEPROP 1 LAST VALUE 100.0
J 2
(-7845 3075);
DISPLAY 0.617021 (-7845 3075);
PAINT SKYBLUE (-7845 3075);
FORCEPROP 1 LAST TOLERANCE 1%
J 2
(-7845 3025);
DISPLAY 0.617021 (-7845 3025);
PAINT SKYBLUE (-7845 3025);
FORCEPROP 1 LAST PACK_TYPE 0402
J 2
(-7840 2825);
DISPLAY 0.617021 (-7840 2825);
PAINT SKYBLUE (-7840 2825);
FORCEPROP 1 LAST MATERIAL CHIP
J 2
(-7840 2925);
DISPLAY 0.617021 (-7840 2925);
PAINT SKYBLUE (-7840 2925);
FORCEPROP 1 LAST WATTAGE 1/16W
J 2
(-7840 2975);
DISPLAY 0.617021 (-7840 2975);
PAINT SKYBLUE (-7840 2975);
FORCEPROP 1 LASTPIN (-7800 2900) $PN 2
J 2
(-7805 2910);
DISPLAY 0.617021 (-7805 2910);
PAINT ORANGE (-7805 2910);
FORCEPROP 1 LASTPIN (-7800 3100) $PN 1
J 2
(-7805 3062);
DISPLAY 0.617021 (-7805 3062);
PAINT ORANGE (-7805 3062);
FORCEPROP 2 LAST SEC_TYPE 0402
J 0
(-7850 3225);
DISPLAY 1.021277 (-7850 3225);
PAINT ORANGE (-7850 3225);
DISPLAY INVISIBLE (-7850 3225);
FORCEPROP 2 LAST CDS_LIB mstr_discrete
J 0
(-7800 3000);
PAINT ORANGE (-7800 3000);
DISPLAY INVISIBLE (-7800 3000);
FORCEPROP 0 LAST BOM_COST PROC_SOCKET
J 0
(-7825 3225);
DISPLAY 1.021277 (-7825 3225);
PAINT ORANGE (-7825 3225);
DISPLAY INVISIBLE (-7825 3225);
FORCEPROP 2 LAST SEC 1
J 0
(-7850 3225);
DISPLAY 0.680851 (-7850 3225);
PAINT MONO (-7850 3225);
DISPLAY INVISIBLE (-7850 3225);
FORCEPROP 2 LAST CDS_LOCATION R4P11
J 2
(-7845 3125);
DISPLAY 0.617021 (-7845 3125);
PAINT AQUA (-7845 3125);
DISPLAY INVISIBLE (-7845 3125);
FORCEPROP 1 LAST PATH I182
J 2
(-7850 3175);
DISPLAY 0.978723 (-7850 3175);
PAINT WHITE (-7850 3175);
DISPLAY INVISIBLE (-7850 3175);
FORCEPROP 0 LAST ROOM CPU0
J 0
(-7825 3225);
DISPLAY 1.021277 (-7825 3225);
PAINT ORANGE (-7825 3225);
DISPLAY INVISIBLE (-7825 3225);
FORCEADD GND..1
(-7800 2575);
FORCEPROP 3 LASTPIN (-7800 2625) SIG_NAME GND\g
J 0
(-7790 2635);
DISPLAY 0.659574 (-7790 2635);
PAINT MONO (-7790 2635);
DISPLAY INVISIBLE (-7790 2635);
FORCEPROP 1 LAST VOLTAGE 0.0V
J 0
(-7845 2532);
DISPLAY 0.340426 (-7845 2532);
PAINT SKYBLUE (-7845 2532);
DISPLAY INVISIBLE (-7845 2532);
FORCEPROP 1 LAST SIZE 1B
J 0
(-7725 2525);
DISPLAY 1.170213 (-7725 2525);
PAINT GREEN (-7725 2525);
DISPLAY INVISIBLE (-7725 2525);
FORCEPROP 2 LAST CDS_LIB mstr_symbols
J 0
(-7800 2575);
PAINT ORANGE (-7800 2575);
DISPLAY INVISIBLE (-7800 2575);
FORCEPROP 1 LAST PATH I183
J 0
(-7725 2575);
DISPLAY 0.872340 (-7725 2575);
PAINT AQUA (-7725 2575);
DISPLAY INVISIBLE (-7725 2575);
FORCEPROP 1 LAST BODY_TYPE PLUMBING
J 0
(-7845 2532);
DISPLAY 0.340426 (-7845 2532);
PAINT GREEN (-7845 2532);
DISPLAY INVISIBLE (-7845 2532);
FORCEPROP 1 LAST HDL_POWER GND
J 0
(-7800 2725);
DISPLAY 0.702128 (-7800 2725);
PAINT GREEN (-7800 2725);
DISPLAY INVISIBLE (-7800 2725);
FORCEADD RES..2
R 2
(-7375 2100);
FORCEPROP 1 LAST LOCATION R6D11
J 2
(-7420 2225);
DISPLAY 0.617021 (-7420 2225);
PAINT AQUA (-7420 2225);
FORCEPROP 1 LAST PART_NUMBER G21796-047
J 2
(-7415 1975);
DISPLAY 0.617021 (-7415 1975);
PAINT BLUE (-7415 1975);
FORCEPROP 1 LAST VALUE 49.9
J 2
(-7420 2175);
DISPLAY 0.617021 (-7420 2175);
PAINT SKYBLUE (-7420 2175);
FORCEPROP 1 LAST TOLERANCE 1%
J 2
(-7420 2125);
DISPLAY 0.617021 (-7420 2125);
PAINT SKYBLUE (-7420 2125);
FORCEPROP 1 LAST PACK_TYPE 0402
J 2
(-7415 1925);
DISPLAY 0.617021 (-7415 1925);
PAINT SKYBLUE (-7415 1925);
FORCEPROP 1 LAST MATERIAL CHIP
J 2
(-7415 2025);
DISPLAY 0.617021 (-7415 2025);
PAINT SKYBLUE (-7415 2025);
FORCEPROP 1 LAST WATTAGE 1/16W
J 2
(-7415 2075);
DISPLAY 0.617021 (-7415 2075);
PAINT SKYBLUE (-7415 2075);
FORCEPROP 1 LASTPIN (-7375 2000) $PN 2
J 2
(-7380 2010);
DISPLAY 0.617021 (-7380 2010);
PAINT WHITE (-7380 2010);
FORCEPROP 1 LASTPIN (-7375 2200) $PN 1
J 2
(-7380 2162);
DISPLAY 0.617021 (-7380 2162);
PAINT WHITE (-7380 2162);
FORCEPROP 2 LAST CDS_LIB mstr_discrete
J 0
(-7375 2100);
PAINT ORANGE (-7375 2100);
DISPLAY INVISIBLE (-7375 2100);
FORCEPROP 0 LAST BOM_COST PROC_SOCKET
J 0
(-7400 2325);
DISPLAY 1.021277 (-7400 2325);
PAINT ORANGE (-7400 2325);
DISPLAY INVISIBLE (-7400 2325);
FORCEPROP 2 LAST SEC_TYPE 0402
J 0
(-7425 2325);
DISPLAY 1.021277 (-7425 2325);
PAINT ORANGE (-7425 2325);
DISPLAY INVISIBLE (-7425 2325);
FORCEPROP 2 LAST SEC 1
J 0
(-7425 2325);
DISPLAY 0.680851 (-7425 2325);
PAINT MONO (-7425 2325);
DISPLAY INVISIBLE (-7425 2325);
FORCEPROP 2 LAST CDS_LOCATION R6D11
J 2
(-7420 2225);
DISPLAY 0.617021 (-7420 2225);
PAINT AQUA (-7420 2225);
DISPLAY INVISIBLE (-7420 2225);
FORCEPROP 1 LAST PATH I184
J 2
(-7425 2275);
DISPLAY 0.978723 (-7425 2275);
PAINT WHITE (-7425 2275);
DISPLAY INVISIBLE (-7425 2275);
FORCEPROP 0 LAST ROOM CPU0
J 0
(-7400 2325);
DISPLAY 1.021277 (-7400 2325);
PAINT ORANGE (-7400 2325);
DISPLAY INVISIBLE (-7400 2325);
FORCEADD RES..2
R 2
(-7575 2100);
FORCEPROP 1 LAST LOCATION R4P3
J 2
(-7620 2225);
DISPLAY 0.617021 (-7620 2225);
PAINT AQUA (-7620 2225);
FORCEPROP 1 LAST PART_NUMBER G21796-047
J 2
(-7615 1975);
DISPLAY 0.617021 (-7615 1975);
PAINT BLUE (-7615 1975);
FORCEPROP 1 LAST VALUE 49.9
J 2
(-7620 2175);
DISPLAY 0.617021 (-7620 2175);
PAINT SKYBLUE (-7620 2175);
FORCEPROP 1 LAST TOLERANCE 1%
J 2
(-7620 2125);
DISPLAY 0.617021 (-7620 2125);
PAINT SKYBLUE (-7620 2125);
FORCEPROP 1 LAST PACK_TYPE 0402
J 2
(-7615 1925);
DISPLAY 0.617021 (-7615 1925);
PAINT SKYBLUE (-7615 1925);
FORCEPROP 1 LAST MATERIAL CHIP
J 2
(-7615 2025);
DISPLAY 0.617021 (-7615 2025);
PAINT SKYBLUE (-7615 2025);
FORCEPROP 1 LAST WATTAGE 1/16W
J 2
(-7615 2075);
DISPLAY 0.617021 (-7615 2075);
PAINT SKYBLUE (-7615 2075);
FORCEPROP 1 LASTPIN (-7575 2000) $PN 2
J 2
(-7580 2010);
DISPLAY 0.617021 (-7580 2010);
PAINT WHITE (-7580 2010);
FORCEPROP 1 LASTPIN (-7575 2200) $PN 1
J 2
(-7580 2162);
DISPLAY 0.617021 (-7580 2162);
PAINT WHITE (-7580 2162);
FORCEPROP 2 LAST CDS_LIB mstr_discrete
J 0
(-7575 2100);
PAINT ORANGE (-7575 2100);
DISPLAY INVISIBLE (-7575 2100);
FORCEPROP 0 LAST BOM_COST PROC_SOCKET
J 0
(-7600 2325);
DISPLAY 1.021277 (-7600 2325);
PAINT ORANGE (-7600 2325);
DISPLAY INVISIBLE (-7600 2325);
FORCEPROP 2 LAST SEC_TYPE 0402
J 0
(-7625 2325);
DISPLAY 1.021277 (-7625 2325);
PAINT ORANGE (-7625 2325);
DISPLAY INVISIBLE (-7625 2325);
FORCEPROP 2 LAST SEC 1
J 0
(-7625 2325);
DISPLAY 0.680851 (-7625 2325);
PAINT MONO (-7625 2325);
DISPLAY INVISIBLE (-7625 2325);
FORCEPROP 2 LAST CDS_LOCATION R4P3
J 2
(-7620 2225);
DISPLAY 0.617021 (-7620 2225);
PAINT AQUA (-7620 2225);
DISPLAY INVISIBLE (-7620 2225);
FORCEPROP 1 LAST PATH I186
J 2
(-7625 2275);
DISPLAY 0.978723 (-7625 2275);
PAINT WHITE (-7625 2275);
DISPLAY INVISIBLE (-7625 2275);
FORCEPROP 0 LAST ROOM CPU0
J 0
(-7600 2325);
DISPLAY 1.021277 (-7600 2325);
PAINT ORANGE (-7600 2325);
DISPLAY INVISIBLE (-7600 2325);
FORCEADD GND..1
(-7800 1725);
FORCEPROP 3 LASTPIN (-7800 1775) SIG_NAME GND\g
J 0
(-7790 1785);
DISPLAY 0.659574 (-7790 1785);
PAINT MONO (-7790 1785);
DISPLAY INVISIBLE (-7790 1785);
FORCEPROP 1 LAST VOLTAGE 0.0V
J 0
(-7845 1682);
DISPLAY 0.340426 (-7845 1682);
PAINT SKYBLUE (-7845 1682);
DISPLAY INVISIBLE (-7845 1682);
FORCEPROP 1 LAST SIZE 1B
J 0
(-7725 1675);
DISPLAY 1.170213 (-7725 1675);
PAINT GREEN (-7725 1675);
DISPLAY INVISIBLE (-7725 1675);
FORCEPROP 2 LAST CDS_LIB mstr_symbols
J 0
(-7800 1725);
PAINT ORANGE (-7800 1725);
DISPLAY INVISIBLE (-7800 1725);
FORCEPROP 1 LAST PATH I187
J 0
(-7725 1725);
DISPLAY 0.872340 (-7725 1725);
PAINT AQUA (-7725 1725);
DISPLAY INVISIBLE (-7725 1725);
FORCEPROP 1 LAST BODY_TYPE PLUMBING
J 0
(-7845 1682);
DISPLAY 0.340426 (-7845 1682);
PAINT GREEN (-7845 1682);
DISPLAY INVISIBLE (-7845 1682);
FORCEPROP 1 LAST HDL_POWER GND
J 0
(-7800 1875);
DISPLAY 0.702128 (-7800 1875);
PAINT GREEN (-7800 1875);
DISPLAY INVISIBLE (-7800 1875);
FORCEADD RES..2
R 2
(-7800 2100);
FORCEPROP 1 LAST LOCATION R4P2
J 2
(-7845 2225);
DISPLAY 0.617021 (-7845 2225);
PAINT AQUA (-7845 2225);
FORCEPROP 1 LAST PART_NUMBER G21796-047
J 2
(-7840 1975);
DISPLAY 0.617021 (-7840 1975);
PAINT BLUE (-7840 1975);
FORCEPROP 1 LAST VALUE 49.9
J 2
(-7845 2175);
DISPLAY 0.617021 (-7845 2175);
PAINT SKYBLUE (-7845 2175);
FORCEPROP 1 LAST TOLERANCE 1%
J 2
(-7845 2125);
DISPLAY 0.617021 (-7845 2125);
PAINT SKYBLUE (-7845 2125);
FORCEPROP 1 LAST PACK_TYPE 0402
J 2
(-7840 1925);
DISPLAY 0.617021 (-7840 1925);
PAINT SKYBLUE (-7840 1925);
FORCEPROP 1 LAST MATERIAL CHIP
J 2
(-7840 2025);
DISPLAY 0.617021 (-7840 2025);
PAINT SKYBLUE (-7840 2025);
FORCEPROP 1 LAST WATTAGE 1/16W
J 2
(-7840 2075);
DISPLAY 0.617021 (-7840 2075);
PAINT SKYBLUE (-7840 2075);
FORCEPROP 1 LASTPIN (-7800 2000) $PN 2
J 2
(-7805 2010);
DISPLAY 0.617021 (-7805 2010);
PAINT WHITE (-7805 2010);
FORCEPROP 1 LASTPIN (-7800 2200) $PN 1
J 2
(-7805 2162);
DISPLAY 0.617021 (-7805 2162);
PAINT WHITE (-7805 2162);
FORCEPROP 2 LAST CDS_LIB mstr_discrete
J 0
(-7800 2100);
PAINT ORANGE (-7800 2100);
DISPLAY INVISIBLE (-7800 2100);
FORCEPROP 0 LAST BOM_COST PROC_SOCKET
J 0
(-7825 2325);
DISPLAY 1.021277 (-7825 2325);
PAINT ORANGE (-7825 2325);
DISPLAY INVISIBLE (-7825 2325);
FORCEPROP 2 LAST SEC_TYPE 0402
J 0
(-7850 2325);
DISPLAY 1.021277 (-7850 2325);
PAINT ORANGE (-7850 2325);
DISPLAY INVISIBLE (-7850 2325);
FORCEPROP 2 LAST SEC 1
J 0
(-7850 2325);
DISPLAY 0.680851 (-7850 2325);
PAINT MONO (-7850 2325);
DISPLAY INVISIBLE (-7850 2325);
FORCEPROP 2 LAST CDS_LOCATION R4P2
J 2
(-7845 2225);
DISPLAY 0.617021 (-7845 2225);
PAINT AQUA (-7845 2225);
DISPLAY INVISIBLE (-7845 2225);
FORCEPROP 1 LAST PATH I188
J 2
(-7850 2275);
DISPLAY 0.978723 (-7850 2275);
PAINT WHITE (-7850 2275);
DISPLAY INVISIBLE (-7850 2275);
FORCEPROP 0 LAST ROOM CPU0
J 0
(-7825 2325);
DISPLAY 1.021277 (-7825 2325);
PAINT ORANGE (-7825 2325);
DISPLAY INVISIBLE (-7825 2325);
FORCEADD RES..2
R 2
(-7150 2050);
FORCEPROP 1 LAST LOCATION R4P4
J 2
(-7195 2175);
DISPLAY 0.617021 (-7195 2175);
PAINT AQUA (-7195 2175);
FORCEPROP 1 LAST PART_NUMBER G21796-047
J 2
(-7190 1925);
DISPLAY 0.617021 (-7190 1925);
PAINT BLUE (-7190 1925);
FORCEPROP 1 LAST VALUE 49.9
J 2
(-7195 2125);
DISPLAY 0.617021 (-7195 2125);
PAINT SKYBLUE (-7195 2125);
FORCEPROP 1 LAST TOLERANCE 1%
J 2
(-7195 2075);
DISPLAY 0.617021 (-7195 2075);
PAINT SKYBLUE (-7195 2075);
FORCEPROP 1 LAST PACK_TYPE 0402
J 2
(-7190 1875);
DISPLAY 0.617021 (-7190 1875);
PAINT SKYBLUE (-7190 1875);
FORCEPROP 1 LAST MATERIAL CHIP
J 2
(-7190 1975);
DISPLAY 0.617021 (-7190 1975);
PAINT SKYBLUE (-7190 1975);
FORCEPROP 1 LAST WATTAGE 1/16W
J 2
(-7190 2025);
DISPLAY 0.617021 (-7190 2025);
PAINT SKYBLUE (-7190 2025);
FORCEPROP 1 LASTPIN (-7150 1950) $PN 2
J 2
(-7155 1960);
DISPLAY 0.617021 (-7155 1960);
PAINT WHITE (-7155 1960);
FORCEPROP 1 LASTPIN (-7150 2150) $PN 1
J 2
(-7155 2112);
DISPLAY 0.617021 (-7155 2112);
PAINT WHITE (-7155 2112);
FORCEPROP 2 LAST SEC_TYPE 0402
J 0
(-7200 2275);
DISPLAY 1.021277 (-7200 2275);
PAINT ORANGE (-7200 2275);
DISPLAY INVISIBLE (-7200 2275);
FORCEPROP 0 LAST BOM_COST PROC_SOCKET
J 0
(-7175 2275);
DISPLAY 1.021277 (-7175 2275);
PAINT ORANGE (-7175 2275);
DISPLAY INVISIBLE (-7175 2275);
FORCEPROP 2 LAST CDS_LIB mstr_discrete
J 0
(-7150 2050);
PAINT ORANGE (-7150 2050);
DISPLAY INVISIBLE (-7150 2050);
FORCEPROP 2 LAST SEC 1
J 0
(-7200 2275);
DISPLAY 0.680851 (-7200 2275);
PAINT MONO (-7200 2275);
DISPLAY INVISIBLE (-7200 2275);
FORCEPROP 2 LAST CDS_LOCATION R4P4
J 2
(-7195 2175);
DISPLAY 0.617021 (-7195 2175);
PAINT AQUA (-7195 2175);
DISPLAY INVISIBLE (-7195 2175);
FORCEPROP 1 LAST PATH I189
J 2
(-7200 2225);
DISPLAY 0.978723 (-7200 2225);
PAINT WHITE (-7200 2225);
DISPLAY INVISIBLE (-7200 2225);
FORCEPROP 0 LAST ROOM CPU0
J 0
(-7175 2275);
DISPLAY 1.021277 (-7175 2275);
PAINT ORANGE (-7175 2275);
DISPLAY INVISIBLE (-7175 2275);
FORCEADD OFFPAGE..4
(-1825 4250);
FORCEPROP 2 LAST $XR0 118 
J 0
(-1639 4250);
DISPLAY 0.638298 (-1639 4250);
PAINT MONO (-1639 4250);
FORCEPROP 2 LAST $XR1 55 
J 0
(-1519 4250);
DISPLAY 0.638298 (-1519 4250);
PAINT MONO (-1519 4250);
FORCEPROP 2 LAST CDS_LIB mstr_standard
J 0
(-1825 4250);
PAINT ORANGE (-1825 4250);
DISPLAY INVISIBLE (-1825 4250);
FORCEPROP 2 LAST PATH I196
J 0
(-1650 4325);
DISPLAY 1.021277 (-1650 4325);
PAINT ORANGE (-1650 4325);
DISPLAY INVISIBLE (-1650 4325);
FORCEPROP 1 LAST OFFPAGE TRUE
J 0
(-1500 4125);
DISPLAY 1.170213 (-1500 4125);
PAINT GREEN (-1500 4125);
DISPLAY INVISIBLE (-1500 4125);
FORCEPROP 1 LAST COMMENT_BODY TRUE
J 0
(-1850 4150);
DISPLAY 1.170213 (-1850 4150);
PAINT PEACH (-1850 4150);
DISPLAY INVISIBLE (-1850 4150);
FORCEADD OFFPAGE..2
(-1850 4350);
FORCEPROP 2 LAST $XR0 90 
J 0
(-1661 4350);
DISPLAY 0.638298 (-1661 4350);
PAINT MONO (-1661 4350);
FORCEPROP 2 LAST CDS_LIB mstr_standard
J 0
(-1850 4350);
PAINT ORANGE (-1850 4350);
DISPLAY INVISIBLE (-1850 4350);
FORCEPROP 2 LAST PATH I197
J 0
(-1675 4425);
DISPLAY 1.021277 (-1675 4425);
PAINT ORANGE (-1675 4425);
DISPLAY INVISIBLE (-1675 4425);
FORCEPROP 1 LAST OFFPAGE TRUE
J 0
(-1525 4225);
DISPLAY 0.872340 (-1525 4225);
PAINT GREEN (-1525 4225);
DISPLAY INVISIBLE (-1525 4225);
FORCEPROP 1 LAST COMMENT_BODY TRUE
J 0
(-1895 4255);
DISPLAY 0.872340 (-1895 4255);
PAINT GREEN (-1895 4255);
DISPLAY INVISIBLE (-1895 4255);
FORCEADD OFFPAGE..1
(-6350 4500);
FORCEPROP 2 LAST $XR0 103 
J 0
(-6602 4500);
DISPLAY 0.638298 (-6602 4500);
PAINT MONO (-6602 4500);
FORCEPROP 2 LAST CDS_LIB mstr_standard
J 0
(-6350 4500);
PAINT MONO (-6350 4500);
DISPLAY INVISIBLE (-6350 4500);
FORCEPROP 2 LAST PATH I2
J 0
(-6650 4550);
DISPLAY 1.361702 (-6650 4550);
PAINT ORANGE (-6650 4550);
DISPLAY INVISIBLE (-6650 4550);
FORCEPROP 1 LAST OFFPAGE TRUE
J 0
(-6025 4375);
DISPLAY 1.170213 (-6025 4375);
PAINT GREEN (-6025 4375);
DISPLAY INVISIBLE (-6025 4375);
FORCEPROP 1 LAST COMMENT_BODY TRUE
J 0
(-6225 4400);
DISPLAY 1.170213 (-6225 4400);
PAINT PEACH (-6225 4400);
DISPLAY INVISIBLE (-6225 4400);
FORCEADD OFFPAGE..2
(-550 1250);
FORCEPROP 2 LAST $XR0 118 
J 0
(-361 1250);
DISPLAY 0.638298 (-361 1250);
PAINT MONO (-361 1250);
FORCEPROP 2 LAST $XR1 144 
J 0
(-241 1250);
DISPLAY 0.638298 (-241 1250);
PAINT MONO (-241 1250);
FORCEPROP 2 LAST $XR2 190 
J 0
(-361 1214);
DISPLAY 0.638298 (-361 1214);
PAINT MONO (-361 1214);
FORCEPROP 2 LAST CDS_LIB mstr_standard
J 0
(-550 1250);
PAINT ORANGE (-550 1250);
DISPLAY INVISIBLE (-550 1250);
FORCEPROP 2 LAST PATH I200
J 0
(-375 1325);
DISPLAY 1.021277 (-375 1325);
PAINT ORANGE (-375 1325);
DISPLAY INVISIBLE (-375 1325);
FORCEPROP 1 LAST OFFPAGE TRUE
J 0
(-225 1125);
DISPLAY 1.170213 (-225 1125);
PAINT GREEN (-225 1125);
DISPLAY INVISIBLE (-225 1125);
FORCEPROP 1 LAST COMMENT_BODY TRUE
J 0
(-595 1155);
DISPLAY 1.170213 (-595 1155);
PAINT PEACH (-595 1155);
DISPLAY INVISIBLE (-595 1155);
FORCEADD OFFPAGE..2
(-2075 2600);
FORCEPROP 2 LAST $XR0 90 
J 0
(-1886 2600);
DISPLAY 0.638298 (-1886 2600);
PAINT MONO (-1886 2600);
FORCEPROP 2 LAST CDS_LIB mstr_standard
J 0
(-2075 2600);
PAINT ORANGE (-2075 2600);
DISPLAY INVISIBLE (-2075 2600);
FORCEPROP 2 LAST PATH I201
J 0
(-1900 2675);
DISPLAY 1.021277 (-1900 2675);
PAINT ORANGE (-1900 2675);
DISPLAY INVISIBLE (-1900 2675);
FORCEPROP 1 LAST OFFPAGE TRUE
J 0
(-1750 2475);
DISPLAY 0.872340 (-1750 2475);
PAINT GREEN (-1750 2475);
DISPLAY INVISIBLE (-1750 2475);
FORCEPROP 1 LAST COMMENT_BODY TRUE
J 0
(-2120 2505);
DISPLAY 0.872340 (-2120 2505);
PAINT GREEN (-2120 2505);
DISPLAY INVISIBLE (-2120 2505);
FORCEADD OFFPAGE..2
(-2075 2650);
FORCEPROP 2 LAST $XR0 90 
J 0
(-1886 2650);
DISPLAY 0.638298 (-1886 2650);
PAINT MONO (-1886 2650);
FORCEPROP 2 LAST CDS_LIB mstr_standard
J 0
(-2075 2650);
PAINT ORANGE (-2075 2650);
DISPLAY INVISIBLE (-2075 2650);
FORCEPROP 2 LAST PATH I202
J 0
(-1900 2725);
DISPLAY 1.021277 (-1900 2725);
PAINT ORANGE (-1900 2725);
DISPLAY INVISIBLE (-1900 2725);
FORCEPROP 1 LAST OFFPAGE TRUE
J 0
(-1750 2525);
DISPLAY 0.872340 (-1750 2525);
PAINT GREEN (-1750 2525);
DISPLAY INVISIBLE (-1750 2525);
FORCEPROP 1 LAST COMMENT_BODY TRUE
J 0
(-2120 2555);
DISPLAY 0.872340 (-2120 2555);
PAINT GREEN (-2120 2555);
DISPLAY INVISIBLE (-2120 2555);
FORCEADD RES..2
R 2
(-6925 2000);
FORCEPROP 1 LAST LOCATION R6D2
J 2
(-6970 2125);
DISPLAY 0.617021 (-6970 2125);
PAINT AQUA (-6970 2125);
FORCEPROP 1 LAST PART_NUMBER G21796-047
J 2
(-6940 1900);
DISPLAY 0.617021 (-6940 1900);
PAINT BLUE (-6940 1900);
FORCEPROP 1 LAST VALUE 49.9
J 2
(-6970 2075);
DISPLAY 0.617021 (-6970 2075);
PAINT SKYBLUE (-6970 2075);
FORCEPROP 1 LAST TOLERANCE 1%
J 2
(-6970 2025);
DISPLAY 0.617021 (-6970 2025);
PAINT SKYBLUE (-6970 2025);
FORCEPROP 1 LAST PACK_TYPE 0402
J 2
(-6940 1850);
DISPLAY 0.617021 (-6940 1850);
PAINT SKYBLUE (-6940 1850);
FORCEPROP 1 LAST MATERIAL CHIP
J 2
(-6965 1950);
DISPLAY 0.617021 (-6965 1950);
PAINT SKYBLUE (-6965 1950);
FORCEPROP 1 LAST WATTAGE 1/16W
J 2
(-6965 1975);
DISPLAY 0.617021 (-6965 1975);
PAINT SKYBLUE (-6965 1975);
FORCEPROP 1 LASTPIN (-6925 1900) $PN 2
J 2
(-6930 1910);
DISPLAY 0.617021 (-6930 1910);
PAINT WHITE (-6930 1910);
FORCEPROP 1 LASTPIN (-6925 2100) $PN 1
J 2
(-6930 2062);
DISPLAY 0.617021 (-6930 2062);
PAINT WHITE (-6930 2062);
FORCEPROP 2 LAST CDS_LIB mstr_discrete
J 0
(-6925 2000);
PAINT ORANGE (-6925 2000);
DISPLAY INVISIBLE (-6925 2000);
FORCEPROP 0 LAST BOM_COST PROC_SOCKET
J 0
(-6950 2225);
DISPLAY 1.021277 (-6950 2225);
PAINT ORANGE (-6950 2225);
DISPLAY INVISIBLE (-6950 2225);
FORCEPROP 2 LAST SEC_TYPE 0402
J 0
(-6975 2225);
DISPLAY 1.021277 (-6975 2225);
PAINT ORANGE (-6975 2225);
DISPLAY INVISIBLE (-6975 2225);
FORCEPROP 2 LAST SEC 1
J 0
(-6975 2225);
DISPLAY 0.680851 (-6975 2225);
PAINT MONO (-6975 2225);
DISPLAY INVISIBLE (-6975 2225);
FORCEPROP 2 LAST CDS_LOCATION R6D2
J 2
(-6970 2125);
DISPLAY 0.617021 (-6970 2125);
PAINT AQUA (-6970 2125);
DISPLAY INVISIBLE (-6970 2125);
FORCEPROP 1 LAST PATH I204
J 2
(-6975 2175);
DISPLAY 0.978723 (-6975 2175);
PAINT WHITE (-6975 2175);
DISPLAY INVISIBLE (-6975 2175);
FORCEPROP 0 LAST ROOM CPU0
J 0
(-6950 2225);
DISPLAY 1.021277 (-6950 2225);
PAINT ORANGE (-6950 2225);
DISPLAY INVISIBLE (-6950 2225);
FORCEADD OFFPAGE..4
(-1800 2100);
FORCEPROP 2 LAST $XR0 97 
J 0
(-1614 2100);
DISPLAY 0.638298 (-1614 2100);
PAINT MONO (-1614 2100);
FORCEPROP 2 LAST CDS_LIB mstr_standard
J 0
(-1800 2100);
PAINT ORANGE (-1800 2100);
DISPLAY INVISIBLE (-1800 2100);
FORCEPROP 2 LAST PATH I205
J 0
(-1625 2175);
DISPLAY 1.021277 (-1625 2175);
PAINT ORANGE (-1625 2175);
DISPLAY INVISIBLE (-1625 2175);
FORCEPROP 1 LAST OFFPAGE TRUE
J 0
(-1475 1975);
DISPLAY 1.170213 (-1475 1975);
PAINT GREEN (-1475 1975);
DISPLAY INVISIBLE (-1475 1975);
FORCEPROP 1 LAST COMMENT_BODY TRUE
J 0
(-1825 2000);
DISPLAY 1.170213 (-1825 2000);
PAINT PEACH (-1825 2000);
DISPLAY INVISIBLE (-1825 2000);
FORCEADD OFFPAGE..4
(-1800 1900);
FORCEPROP 2 LAST $XR0 90 
J 0
(-1614 1900);
DISPLAY 0.638298 (-1614 1900);
PAINT MONO (-1614 1900);
FORCEPROP 2 LAST CDS_LIB mstr_standard
J 0
(-1800 1900);
PAINT ORANGE (-1800 1900);
DISPLAY INVISIBLE (-1800 1900);
FORCEPROP 2 LAST PATH I209
J 0
(-1625 1975);
DISPLAY 1.021277 (-1625 1975);
PAINT ORANGE (-1625 1975);
DISPLAY INVISIBLE (-1625 1975);
FORCEPROP 1 LAST OFFPAGE TRUE
J 0
(-1475 1775);
DISPLAY 1.170213 (-1475 1775);
PAINT GREEN (-1475 1775);
DISPLAY INVISIBLE (-1475 1775);
FORCEPROP 1 LAST COMMENT_BODY TRUE
J 0
(-1825 1800);
DISPLAY 1.170213 (-1825 1800);
PAINT PEACH (-1825 1800);
DISPLAY INVISIBLE (-1825 1800);
FORCEADD OFFPAGE..5
(-6350 3600);
FORCEPROP 2 LAST $XR0 98 
J 0
(-6574 3600);
DISPLAY 0.638298 (-6574 3600);
PAINT MONO (-6574 3600);
FORCEPROP 2 LAST CDS_LIB mstr_standard
J 0
(-6350 3600);
PAINT ORANGE (-6350 3600);
DISPLAY INVISIBLE (-6350 3600);
FORCEPROP 2 LAST PATH I212
J 0
(-6300 3675);
DISPLAY 1.021277 (-6300 3675);
PAINT ORANGE (-6300 3675);
DISPLAY INVISIBLE (-6300 3675);
FORCEPROP 1 LAST OFFPAGE TRUE
J 0
(-6025 3475);
DISPLAY 1.170213 (-6025 3475);
PAINT GREEN (-6025 3475);
DISPLAY INVISIBLE (-6025 3475);
FORCEPROP 1 LAST COMMENT_BODY TRUE
J 0
(-6250 3525);
DISPLAY 1.170213 (-6250 3525);
PAINT PEACH (-6250 3525);
DISPLAY INVISIBLE (-6250 3525);
FORCEADD OFFPAGE..5
(-6350 3550);
FORCEPROP 2 LAST $XR0 98 
J 0
(-6574 3550);
DISPLAY 0.638298 (-6574 3550);
PAINT MONO (-6574 3550);
FORCEPROP 2 LAST CDS_LIB mstr_standard
J 0
(-6350 3550);
PAINT ORANGE (-6350 3550);
DISPLAY INVISIBLE (-6350 3550);
FORCEPROP 2 LAST PATH I213
J 0
(-6300 3625);
DISPLAY 1.021277 (-6300 3625);
PAINT ORANGE (-6300 3625);
DISPLAY INVISIBLE (-6300 3625);
FORCEPROP 1 LAST OFFPAGE TRUE
J 0
(-6025 3425);
DISPLAY 1.170213 (-6025 3425);
PAINT GREEN (-6025 3425);
DISPLAY INVISIBLE (-6025 3425);
FORCEPROP 1 LAST COMMENT_BODY TRUE
J 0
(-6250 3475);
DISPLAY 1.170213 (-6250 3475);
PAINT PEACH (-6250 3475);
DISPLAY INVISIBLE (-6250 3475);
FORCEADD OFFPAGE..5
(-6350 3400);
FORCEPROP 2 LAST $XR0 98 
J 0
(-6574 3400);
DISPLAY 0.638298 (-6574 3400);
PAINT MONO (-6574 3400);
FORCEPROP 2 LAST CDS_LIB mstr_standard
J 0
(-6350 3400);
PAINT ORANGE (-6350 3400);
DISPLAY INVISIBLE (-6350 3400);
FORCEPROP 2 LAST PATH I214
J 0
(-6300 3475);
DISPLAY 1.021277 (-6300 3475);
PAINT ORANGE (-6300 3475);
DISPLAY INVISIBLE (-6300 3475);
FORCEPROP 1 LAST OFFPAGE TRUE
J 0
(-6025 3275);
DISPLAY 1.170213 (-6025 3275);
PAINT GREEN (-6025 3275);
DISPLAY INVISIBLE (-6025 3275);
FORCEPROP 1 LAST COMMENT_BODY TRUE
J 0
(-6250 3325);
DISPLAY 1.170213 (-6250 3325);
PAINT PEACH (-6250 3325);
DISPLAY INVISIBLE (-6250 3325);
FORCEADD OFFPAGE..5
(-6350 3450);
FORCEPROP 2 LAST $XR0 98 
J 0
(-6574 3450);
DISPLAY 0.638298 (-6574 3450);
PAINT MONO (-6574 3450);
FORCEPROP 2 LAST CDS_LIB mstr_standard
J 0
(-6350 3450);
PAINT ORANGE (-6350 3450);
DISPLAY INVISIBLE (-6350 3450);
FORCEPROP 2 LAST PATH I215
J 0
(-6300 3525);
DISPLAY 1.021277 (-6300 3525);
PAINT ORANGE (-6300 3525);
DISPLAY INVISIBLE (-6300 3525);
FORCEPROP 1 LAST OFFPAGE TRUE
J 0
(-6025 3325);
DISPLAY 1.170213 (-6025 3325);
PAINT GREEN (-6025 3325);
DISPLAY INVISIBLE (-6025 3325);
FORCEPROP 1 LAST COMMENT_BODY TRUE
J 0
(-6250 3375);
DISPLAY 1.170213 (-6250 3375);
PAINT PEACH (-6250 3375);
DISPLAY INVISIBLE (-6250 3375);
FORCEADD SOCKET_P_MECH_A..1
(-7525 4450);
FORCEPROP 1 LAST PACK_TYPE RIGHT
J 0
(-7420 4425);
DISPLAY 0.617021 (-7420 4425);
PAINT SKYBLUE (-7420 4425);
FORCEPROP 1 LAST MATERIAL PLASTIC
J 0
(-7875 4575);
DISPLAY 0.617021 (-7875 4575);
PAINT SKYBLUE (-7875 4575);
FORCEPROP 1 LAST PART_NUMBER H37604-101
J 0
(-7875 4350);
DISPLAY 0.617021 (-7875 4350);
PAINT BLUE (-7875 4350);
FORCEPROP 1 LAST SKT_NUMBER P0
J 0
(-7850 4425);
DISPLAY 0.808511 (-7850 4425);
PAINT GREEN (-7850 4425);
FORCEPROP 1 LAST LOCATION XRU1
J 0
(-7875 4525);
DISPLAY 0.617021 (-7875 4525);
PAINT AQUA (-7875 4525);
FORCEPROP 2 LAST CDS_LIB chpset_lib
J 0
(-7525 4450);
PAINT ORANGE (-7525 4450);
DISPLAY INVISIBLE (-7525 4450);
FORCEPROP 0 LAST BOM_COST PROC_SOCKET
J 0
(-7875 4775);
DISPLAY 1.021277 (-7875 4775);
PAINT ORANGE (-7875 4775);
DISPLAY INVISIBLE (-7875 4775);
FORCEPROP 2 LAST CDS_LOCATION XRU1
J 0
(-7875 4525);
DISPLAY 0.617021 (-7875 4525);
PAINT AQUA (-7875 4525);
DISPLAY INVISIBLE (-7875 4525);
FORCEPROP 1 LAST PATH I216
J 0
(-7525 4570);
DISPLAY 0.872340 (-7525 4570);
PAINT WHITE (-7525 4570);
DISPLAY INVISIBLE (-7525 4570);
FORCEPROP 0 LAST ROOM CPU0
J 0
(-7875 4675);
DISPLAY 1.021277 (-7875 4675);
PAINT ORANGE (-7875 4675);
DISPLAY INVISIBLE (-7875 4675);
FORCEADD SOCKET_P_MECH_A..1
(-7525 4150);
FORCEPROP 1 LAST MATERIAL PLASTIC
J 0
(-7875 4275);
DISPLAY 0.617021 (-7875 4275);
PAINT SKYBLUE (-7875 4275);
FORCEPROP 1 LAST PART_NUMBER H37604-201
J 0
(-7875 4050);
DISPLAY 0.617021 (-7875 4050);
PAINT BLUE (-7875 4050);
FORCEPROP 1 LAST SKT_NUMBER P0
J 0
(-7850 4125);
DISPLAY 0.808511 (-7850 4125);
PAINT GREEN (-7850 4125);
FORCEPROP 1 LAST LOCATION XLU1
J 0
(-7875 4225);
DISPLAY 0.617021 (-7875 4225);
PAINT AQUA (-7875 4225);
FORCEPROP 1 LAST PACK_TYPE LEFT
J 0
(-7420 4125);
DISPLAY 0.617021 (-7420 4125);
PAINT SKYBLUE (-7420 4125);
FORCEPROP 0 LAST BOM_COST PROC_SOCKET
J 0
(-7875 4475);
DISPLAY 1.021277 (-7875 4475);
PAINT ORANGE (-7875 4475);
DISPLAY INVISIBLE (-7875 4475);
FORCEPROP 2 LAST CDS_LIB chpset_lib
J 0
(-7525 4150);
PAINT ORANGE (-7525 4150);
DISPLAY INVISIBLE (-7525 4150);
FORCEPROP 2 LAST CDS_LOCATION XLU1
J 0
(-7875 4225);
DISPLAY 0.617021 (-7875 4225);
PAINT AQUA (-7875 4225);
DISPLAY INVISIBLE (-7875 4225);
FORCEPROP 1 LAST PATH I217
J 0
(-7525 4270);
DISPLAY 0.872340 (-7525 4270);
PAINT WHITE (-7525 4270);
DISPLAY INVISIBLE (-7525 4270);
FORCEPROP 0 LAST ROOM CPU0
J 0
(-7875 4375);
DISPLAY 1.021277 (-7875 4375);
PAINT ORANGE (-7875 4375);
DISPLAY INVISIBLE (-7875 4375);
FORCEADD RES..1
(-2375 4200);
FORCEPROP 1 LAST LOCATION R4P19
J 0
(-2375 4300);
DISPLAY 0.617021 (-2375 4300);
PAINT AQUA (-2375 4300);
FORCEPROP 1 LAST PART_NUMBER G21796-047
J 0
(-2100 4150);
DISPLAY 0.617021 (-2100 4150);
PAINT BLUE (-2100 4150);
FORCEPROP 1 LAST VALUE 49.9
J 2
(-2400 4150);
DISPLAY 0.617021 (-2400 4150);
PAINT SKYBLUE (-2400 4150);
FORCEPROP 1 LAST TOLERANCE 1%
J 0
(-2375 4150);
DISPLAY 0.617021 (-2375 4150);
PAINT SKYBLUE (-2375 4150);
FORCEPROP 1 LAST PACK_TYPE 0402
J 0
(-2200 4150);
DISPLAY 0.617021 (-2200 4150);
PAINT SKYBLUE (-2200 4150);
FORCEPROP 1 LAST MATERIAL CHIP
J 0
(-2300 4150);
DISPLAY 0.617021 (-2300 4150);
PAINT SKYBLUE (-2300 4150);
FORCEPROP 1 LAST WATTAGE 1/16W
J 2
(-2500 4150);
DISPLAY 0.617021 (-2500 4150);
PAINT SKYBLUE (-2500 4150);
FORCEPROP 1 LASTPIN (-2275 4200) $PN 2
J 0
(-2313 4212);
DISPLAY 0.617021 (-2313 4212);
PAINT ORANGE (-2313 4212);
FORCEPROP 1 LASTPIN (-2475 4200) $PN 1
J 0
(-2463 4212);
DISPLAY 0.617021 (-2463 4212);
PAINT ORANGE (-2463 4212);
FORCEPROP 2 LAST CDS_LIB mstr_discrete
J 0
(-2375 4200);
PAINT ORANGE (-2375 4200);
DISPLAY INVISIBLE (-2375 4200);
FORCEPROP 2 LAST SEC_TYPE 0402
J 0
(-2425 4400);
DISPLAY 1.021277 (-2425 4400);
PAINT ORANGE (-2425 4400);
DISPLAY INVISIBLE (-2425 4400);
FORCEPROP 0 LAST BOM_COST PROC_SOCKET
J 0
(-2375 4400);
DISPLAY 1.021277 (-2375 4400);
PAINT ORANGE (-2375 4400);
DISPLAY INVISIBLE (-2375 4400);
FORCEPROP 2 LAST SEC 1
J 0
(-2425 4400);
DISPLAY 0.680851 (-2425 4400);
PAINT MONO (-2425 4400);
DISPLAY INVISIBLE (-2425 4400);
FORCEPROP 2 LAST CDS_LOCATION R4P19
J 0
(-2375 4300);
DISPLAY 0.617021 (-2375 4300);
PAINT AQUA (-2375 4300);
DISPLAY INVISIBLE (-2375 4300);
FORCEPROP 1 LAST PATH I219
J 0
(-2425 4350);
DISPLAY 0.978723 (-2425 4350);
PAINT WHITE (-2425 4350);
DISPLAY INVISIBLE (-2425 4350);
FORCEPROP 0 LAST ROOM CPU0
J 0
(-2425 4400);
DISPLAY 1.021277 (-2425 4400);
PAINT ORANGE (-2425 4400);
DISPLAY INVISIBLE (-2425 4400);
FORCEADD RES..2
(-1475 2700);
FORCEPROP 1 LAST LOCATION R5N2
J 2
(-1325 2825);
DISPLAY 0.617021 (-1325 2825);
PAINT AQUA (-1325 2825);
FORCEPROP 1 LAST PART_NUMBER G21796-336
J 0
(-1435 2575);
DISPLAY 0.617021 (-1435 2575);
PAINT BLUE (-1435 2575);
FORCEPROP 1 LAST VALUE 1.8K
J 0
(-1430 2775);
DISPLAY 0.617021 (-1430 2775);
PAINT SKYBLUE (-1430 2775);
FORCEPROP 1 LAST TOLERANCE 1%
J 0
(-1430 2725);
DISPLAY 0.617021 (-1430 2725);
PAINT SKYBLUE (-1430 2725);
FORCEPROP 1 LAST PACK_TYPE 0402
J 0
(-1435 2525);
DISPLAY 0.617021 (-1435 2525);
PAINT SKYBLUE (-1435 2525);
FORCEPROP 1 LAST MATERIAL CHIP
J 0
(-1435 2625);
DISPLAY 0.617021 (-1435 2625);
PAINT SKYBLUE (-1435 2625);
FORCEPROP 1 LAST WATTAGE 1/16W
J 0
(-1435 2675);
DISPLAY 0.617021 (-1435 2675);
PAINT SKYBLUE (-1435 2675);
FORCEPROP 1 LASTPIN (-1475 2600) $PN 2
J 0
(-1470 2610);
DISPLAY 0.617021 (-1470 2610);
PAINT ORANGE (-1470 2610);
FORCEPROP 1 LASTPIN (-1475 2800) $PN 1
J 0
(-1470 2762);
DISPLAY 0.617021 (-1470 2762);
PAINT ORANGE (-1470 2762);
FORCEPROP 2 LAST CDS_LIB mstr_discrete
J 2
(-1475 2700);
PAINT ORANGE (-1475 2700);
DISPLAY INVISIBLE (-1475 2700);
FORCEPROP 2 LAST SEC_TYPE 0402
J 0
(-1425 2925);
DISPLAY 1.021277 (-1425 2925);
PAINT ORANGE (-1425 2925);
DISPLAY INVISIBLE (-1425 2925);
FORCEPROP 2 LAST BOM_COST PROC_SIDEBAND
J 0
(-1475 2700);
PAINT WHITE (-1475 2700);
DISPLAY INVISIBLE (-1475 2700);
FORCEPROP 2 LAST SEC 1
J 0
(-1425 2925);
DISPLAY 0.680851 (-1425 2925);
PAINT MONO (-1425 2925);
DISPLAY INVISIBLE (-1425 2925);
FORCEPROP 2 LAST CDS_LOCATION R5N2
J 2
(-1325 2825);
DISPLAY 0.617021 (-1325 2825);
PAINT AQUA (-1325 2825);
DISPLAY INVISIBLE (-1325 2825);
FORCEPROP 1 LAST PATH I227
J 0
(-1425 2875);
DISPLAY 0.978723 (-1425 2875);
PAINT WHITE (-1425 2875);
DISPLAY INVISIBLE (-1425 2875);
FORCEPROP 2 LAST ROOM CPU0
J 0
(-1450 2475);
PAINT WHITE (-1450 2475);
DISPLAY INVISIBLE (-1450 2475);
FORCEADD P3V3_STBY..1
(-675 3050);
FORCEPROP 3 LASTPIN (-675 3000) SIG_NAME P3V3_STBY\g
J 0
(-665 3010);
DISPLAY 0.659574 (-665 3010);
PAINT MONO (-665 3010);
DISPLAY INVISIBLE (-665 3010);
FORCEPROP 1 LAST VOLTAGE 3.3V
J 0
(-720 3007);
DISPLAY 0.340426 (-720 3007);
PAINT SKYBLUE (-720 3007);
DISPLAY INVISIBLE (-720 3007);
FORCEPROP 2 LAST CDS_LIB mstr_symbols
J 0
(-675 3050);
PAINT ORANGE (-675 3050);
DISPLAY INVISIBLE (-675 3050);
FORCEPROP 1 LAST SIZE 1B
J 0
(-630 3072);
DISPLAY 0.340426 (-630 3072);
PAINT GREEN (-630 3072);
DISPLAY INVISIBLE (-630 3072);
FORCEPROP 1 LAST PATH I228
J 0
(-630 3052);
DISPLAY 0.340426 (-630 3052);
PAINT GREEN (-630 3052);
DISPLAY INVISIBLE (-630 3052);
FORCEPROP 1 LAST BODY_TYPE PLUMBING
J 0
(-720 3007);
DISPLAY 0.340426 (-720 3007);
PAINT GREEN (-720 3007);
DISPLAY INVISIBLE (-720 3007);
FORCEPROP 1 LAST HDL_POWER P3V3_STBY
J 0
(-975 2925);
DISPLAY 0.872340 (-975 2925);
PAINT GREEN (-975 2925);
DISPLAY INVISIBLE (-975 2925);
FORCEADD OFFPAGE..2
(-550 2450);
FORCEPROP 2 LAST $XR0 147 
J 0
(-361 2450);
DISPLAY 0.638298 (-361 2450);
PAINT MONO (-361 2450);
FORCEPROP 2 LAST $XR1 190 
J 0
(-361 2450);
DISPLAY 0.638298 (-361 2450);
PAINT MONO (-361 2450);
FORCEPROP 2 LAST CDS_LIB mstr_standard
J 0
(-550 2450);
PAINT ORANGE (-550 2450);
DISPLAY INVISIBLE (-550 2450);
FORCEPROP 2 LAST PATH I233
J 0
(-375 2525);
DISPLAY 1.021277 (-375 2525);
PAINT ORANGE (-375 2525);
DISPLAY INVISIBLE (-375 2525);
FORCEPROP 1 LAST OFFPAGE TRUE
J 0
(-225 2325);
DISPLAY 1.170213 (-225 2325);
PAINT GREEN (-225 2325);
DISPLAY INVISIBLE (-225 2325);
FORCEPROP 1 LAST COMMENT_BODY TRUE
J 0
(-595 2355);
DISPLAY 1.170213 (-595 2355);
PAINT PEACH (-595 2355);
DISPLAY INVISIBLE (-595 2355);
FORCEADD OFFPAGE..2
(-550 2400);
FORCEPROP 2 LAST $XR0 147 
J 0
(-361 2400);
DISPLAY 0.638298 (-361 2400);
PAINT MONO (-361 2400);
FORCEPROP 2 LAST $XR1 190 
J 0
(-361 2400);
DISPLAY 0.638298 (-361 2400);
PAINT MONO (-361 2400);
FORCEPROP 2 LAST CDS_LIB mstr_standard
J 0
(-550 2400);
PAINT ORANGE (-550 2400);
DISPLAY INVISIBLE (-550 2400);
FORCEPROP 2 LAST PATH I234
J 0
(-375 2475);
DISPLAY 1.021277 (-375 2475);
PAINT ORANGE (-375 2475);
DISPLAY INVISIBLE (-375 2475);
FORCEPROP 1 LAST OFFPAGE TRUE
J 0
(-225 2275);
DISPLAY 1.170213 (-225 2275);
PAINT GREEN (-225 2275);
DISPLAY INVISIBLE (-225 2275);
FORCEPROP 1 LAST COMMENT_BODY TRUE
J 0
(-595 2305);
DISPLAY 1.170213 (-595 2305);
PAINT PEACH (-595 2305);
DISPLAY INVISIBLE (-595 2305);
FORCEADD OFFPAGE..2
(-550 2300);
FORCEPROP 2 LAST $XR0 190 
J 0
(-361 2300);
DISPLAY 0.638298 (-361 2300);
PAINT MONO (-361 2300);
FORCEPROP 2 LAST CDS_LIB mstr_standard
J 0
(-550 2300);
PAINT ORANGE (-550 2300);
DISPLAY INVISIBLE (-550 2300);
FORCEPROP 2 LAST PATH I235
J 0
(-375 2375);
DISPLAY 1.021277 (-375 2375);
PAINT ORANGE (-375 2375);
DISPLAY INVISIBLE (-375 2375);
FORCEPROP 1 LAST OFFPAGE TRUE
J 0
(-225 2175);
DISPLAY 1.170213 (-225 2175);
PAINT GREEN (-225 2175);
DISPLAY INVISIBLE (-225 2175);
FORCEPROP 1 LAST COMMENT_BODY TRUE
J 0
(-595 2205);
DISPLAY 1.170213 (-595 2205);
PAINT PEACH (-595 2205);
DISPLAY INVISIBLE (-595 2205);
FORCEADD OFFPAGE..2
(-550 2250);
FORCEPROP 2 LAST $XR0 113 
J 0
(-361 2250);
DISPLAY 0.638298 (-361 2250);
PAINT MONO (-361 2250);
FORCEPROP 2 LAST $XR1 190 
J 0
(-241 2250);
DISPLAY 0.638298 (-241 2250);
PAINT MONO (-241 2250);
FORCEPROP 2 LAST CDS_LIB mstr_standard
J 0
(-550 2250);
PAINT ORANGE (-550 2250);
DISPLAY INVISIBLE (-550 2250);
FORCEPROP 2 LAST PATH I236
J 0
(-375 2325);
DISPLAY 1.021277 (-375 2325);
PAINT ORANGE (-375 2325);
DISPLAY INVISIBLE (-375 2325);
FORCEPROP 1 LAST OFFPAGE TRUE
J 0
(-225 2125);
DISPLAY 1.170213 (-225 2125);
PAINT GREEN (-225 2125);
DISPLAY INVISIBLE (-225 2125);
FORCEPROP 1 LAST COMMENT_BODY TRUE
J 0
(-595 2155);
DISPLAY 1.170213 (-595 2155);
PAINT PEACH (-595 2155);
DISPLAY INVISIBLE (-595 2155);
FORCEADD OFFPAGE..2
(-550 2200);
FORCEPROP 2 LAST $XR0 190 
J 0
(-361 2200);
DISPLAY 0.638298 (-361 2200);
PAINT MONO (-361 2200);
FORCEPROP 2 LAST CDS_LIB mstr_standard
J 0
(-550 2200);
PAINT ORANGE (-550 2200);
DISPLAY INVISIBLE (-550 2200);
FORCEPROP 2 LAST PATH I237
J 0
(-375 2275);
DISPLAY 1.021277 (-375 2275);
PAINT ORANGE (-375 2275);
DISPLAY INVISIBLE (-375 2275);
FORCEPROP 1 LAST OFFPAGE TRUE
J 0
(-225 2075);
DISPLAY 1.170213 (-225 2075);
PAINT GREEN (-225 2075);
DISPLAY INVISIBLE (-225 2075);
FORCEPROP 1 LAST COMMENT_BODY TRUE
J 0
(-595 2105);
DISPLAY 1.170213 (-595 2105);
PAINT PEACH (-595 2105);
DISPLAY INVISIBLE (-595 2105);
FORCEADD RES..2
(-675 2700);
FORCEPROP 1 LAST LOCATION R5N1
J 0
(-630 2825);
DISPLAY 0.617021 (-630 2825);
PAINT AQUA (-630 2825);
FORCEPROP 1 LAST PART_NUMBER G21796-016
J 0
(-635 2575);
DISPLAY 0.617021 (-635 2575);
PAINT BLUE (-635 2575);
FORCEPROP 1 LAST VALUE 10.0K
J 0
(-630 2775);
DISPLAY 0.617021 (-630 2775);
PAINT SKYBLUE (-630 2775);
FORCEPROP 1 LAST TOLERANCE 1%
J 0
(-630 2725);
DISPLAY 0.617021 (-630 2725);
PAINT SKYBLUE (-630 2725);
FORCEPROP 1 LAST PACK_TYPE 0402
J 0
(-635 2525);
DISPLAY 0.617021 (-635 2525);
PAINT SKYBLUE (-635 2525);
FORCEPROP 1 LAST MATERIAL CHIP
J 0
(-635 2625);
DISPLAY 0.617021 (-635 2625);
PAINT SKYBLUE (-635 2625);
FORCEPROP 1 LAST WATTAGE 1/16W
J 0
(-635 2675);
DISPLAY 0.617021 (-635 2675);
PAINT SKYBLUE (-635 2675);
FORCEPROP 1 LASTPIN (-675 2600) $PN 2
J 0
(-670 2610);
DISPLAY 0.617021 (-670 2610);
PAINT ORANGE (-670 2610);
FORCEPROP 1 LASTPIN (-675 2800) $PN 1
J 0
(-670 2762);
DISPLAY 0.617021 (-670 2762);
PAINT ORANGE (-670 2762);
FORCEPROP 2 LAST CDS_LIB mstr_discrete
J 2
(-675 2700);
PAINT ORANGE (-675 2700);
DISPLAY INVISIBLE (-675 2700);
FORCEPROP 2 LAST SEC_TYPE 0402
J 0
(-625 2925);
DISPLAY 1.021277 (-625 2925);
PAINT ORANGE (-625 2925);
DISPLAY INVISIBLE (-625 2925);
FORCEPROP 2 LAST BOM_COST PROC_SIDEBAND
J 0
(-675 2700);
PAINT WHITE (-675 2700);
DISPLAY INVISIBLE (-675 2700);
FORCEPROP 2 LAST SEC 1
J 0
(-625 2925);
DISPLAY 0.680851 (-625 2925);
PAINT MONO (-625 2925);
DISPLAY INVISIBLE (-625 2925);
FORCEPROP 2 LAST CDS_LOCATION R5N1
J 0
(-630 2825);
DISPLAY 0.617021 (-630 2825);
PAINT AQUA (-630 2825);
DISPLAY INVISIBLE (-630 2825);
FORCEPROP 1 LAST PATH I238
J 0
(-625 2875);
DISPLAY 0.978723 (-625 2875);
PAINT WHITE (-625 2875);
DISPLAY INVISIBLE (-625 2875);
FORCEPROP 2 LAST ROOM CPU0
J 0
(-650 2475);
PAINT WHITE (-650 2475);
DISPLAY INVISIBLE (-650 2475);
FORCEADD RES..2
(-875 2700);
FORCEPROP 1 LAST LOCATION R5N5
J 0
(-830 2825);
DISPLAY 0.617021 (-830 2825);
PAINT AQUA (-830 2825);
FORCEPROP 1 LAST PART_NUMBER G21796-016
J 0
(-835 2575);
DISPLAY 0.617021 (-835 2575);
PAINT BLUE (-835 2575);
FORCEPROP 1 LAST VALUE 10.0K
J 0
(-830 2775);
DISPLAY 0.617021 (-830 2775);
PAINT SKYBLUE (-830 2775);
FORCEPROP 1 LAST TOLERANCE 1%
J 0
(-830 2725);
DISPLAY 0.617021 (-830 2725);
PAINT SKYBLUE (-830 2725);
FORCEPROP 1 LAST PACK_TYPE 0402
J 0
(-835 2525);
DISPLAY 0.617021 (-835 2525);
PAINT SKYBLUE (-835 2525);
FORCEPROP 1 LAST MATERIAL CHIP
J 0
(-835 2625);
DISPLAY 0.617021 (-835 2625);
PAINT SKYBLUE (-835 2625);
FORCEPROP 1 LAST WATTAGE 1/16W
J 0
(-835 2675);
DISPLAY 0.617021 (-835 2675);
PAINT SKYBLUE (-835 2675);
FORCEPROP 1 LASTPIN (-875 2600) $PN 2
J 0
(-870 2610);
DISPLAY 0.617021 (-870 2610);
PAINT ORANGE (-870 2610);
FORCEPROP 1 LASTPIN (-875 2800) $PN 1
J 0
(-870 2762);
DISPLAY 0.617021 (-870 2762);
PAINT ORANGE (-870 2762);
FORCEPROP 2 LAST CDS_LIB mstr_discrete
J 2
(-875 2700);
PAINT ORANGE (-875 2700);
DISPLAY INVISIBLE (-875 2700);
FORCEPROP 2 LAST SEC_TYPE 0402
J 0
(-825 2925);
DISPLAY 1.021277 (-825 2925);
PAINT ORANGE (-825 2925);
DISPLAY INVISIBLE (-825 2925);
FORCEPROP 2 LAST BOM_COST PROC_SIDEBAND
J 0
(-875 2700);
PAINT WHITE (-875 2700);
DISPLAY INVISIBLE (-875 2700);
FORCEPROP 2 LAST SEC 1
J 0
(-825 2925);
DISPLAY 0.680851 (-825 2925);
PAINT MONO (-825 2925);
DISPLAY INVISIBLE (-825 2925);
FORCEPROP 2 LAST CDS_LOCATION R5N5
J 0
(-830 2825);
DISPLAY 0.617021 (-830 2825);
PAINT AQUA (-830 2825);
DISPLAY INVISIBLE (-830 2825);
FORCEPROP 1 LAST PATH I239
J 0
(-825 2875);
DISPLAY 0.978723 (-825 2875);
PAINT WHITE (-825 2875);
DISPLAY INVISIBLE (-825 2875);
FORCEPROP 2 LAST ROOM CPU0
J 0
(-850 2475);
PAINT WHITE (-850 2475);
DISPLAY INVISIBLE (-850 2475);
FORCEADD RES..2
(-1075 2700);
FORCEPROP 1 LAST LOCATION R5N3
J 0
(-1030 2825);
DISPLAY 0.617021 (-1030 2825);
PAINT AQUA (-1030 2825);
FORCEPROP 1 LAST PART_NUMBER G21796-016
J 0
(-1035 2575);
DISPLAY 0.617021 (-1035 2575);
PAINT BLUE (-1035 2575);
FORCEPROP 1 LAST VALUE 10.0K
J 0
(-1030 2775);
DISPLAY 0.617021 (-1030 2775);
PAINT SKYBLUE (-1030 2775);
FORCEPROP 1 LAST TOLERANCE 1%
J 0
(-1030 2725);
DISPLAY 0.617021 (-1030 2725);
PAINT SKYBLUE (-1030 2725);
FORCEPROP 1 LAST PACK_TYPE 0402
J 0
(-1035 2525);
DISPLAY 0.617021 (-1035 2525);
PAINT SKYBLUE (-1035 2525);
FORCEPROP 1 LAST MATERIAL CHIP
J 0
(-1035 2625);
DISPLAY 0.617021 (-1035 2625);
PAINT SKYBLUE (-1035 2625);
FORCEPROP 1 LAST WATTAGE 1/16W
J 0
(-1035 2675);
DISPLAY 0.617021 (-1035 2675);
PAINT SKYBLUE (-1035 2675);
FORCEPROP 1 LASTPIN (-1075 2600) $PN 2
J 0
(-1070 2610);
DISPLAY 0.617021 (-1070 2610);
PAINT ORANGE (-1070 2610);
FORCEPROP 1 LASTPIN (-1075 2800) $PN 1
J 0
(-1070 2762);
DISPLAY 0.617021 (-1070 2762);
PAINT ORANGE (-1070 2762);
FORCEPROP 2 LAST CDS_LIB mstr_discrete
J 2
(-1075 2700);
PAINT ORANGE (-1075 2700);
DISPLAY INVISIBLE (-1075 2700);
FORCEPROP 2 LAST SEC_TYPE 0402
J 0
(-1025 2925);
DISPLAY 1.021277 (-1025 2925);
PAINT ORANGE (-1025 2925);
DISPLAY INVISIBLE (-1025 2925);
FORCEPROP 2 LAST BOM_COST PROC_SIDEBAND
J 0
(-1075 2700);
PAINT WHITE (-1075 2700);
DISPLAY INVISIBLE (-1075 2700);
FORCEPROP 2 LAST SEC 1
J 0
(-1025 2925);
DISPLAY 0.680851 (-1025 2925);
PAINT MONO (-1025 2925);
DISPLAY INVISIBLE (-1025 2925);
FORCEPROP 2 LAST CDS_LOCATION R5N3
J 0
(-1030 2825);
DISPLAY 0.617021 (-1030 2825);
PAINT AQUA (-1030 2825);
DISPLAY INVISIBLE (-1030 2825);
FORCEPROP 1 LAST PATH I240
J 0
(-1025 2875);
DISPLAY 0.978723 (-1025 2875);
PAINT WHITE (-1025 2875);
DISPLAY INVISIBLE (-1025 2875);
FORCEPROP 2 LAST ROOM CPU0
J 0
(-1050 2475);
PAINT WHITE (-1050 2475);
DISPLAY INVISIBLE (-1050 2475);
FORCEADD RES..2
(-1275 2700);
FORCEPROP 1 LAST LOCATION R5N4
J 0
(-1230 2825);
DISPLAY 0.617021 (-1230 2825);
PAINT AQUA (-1230 2825);
FORCEPROP 1 LAST PART_NUMBER G21796-336
J 0
(-1235 2575);
DISPLAY 0.617021 (-1235 2575);
PAINT BLUE (-1235 2575);
FORCEPROP 1 LAST VALUE 1.8K
J 0
(-1230 2775);
DISPLAY 0.617021 (-1230 2775);
PAINT SKYBLUE (-1230 2775);
FORCEPROP 1 LAST TOLERANCE 1%
J 0
(-1230 2725);
DISPLAY 0.617021 (-1230 2725);
PAINT SKYBLUE (-1230 2725);
FORCEPROP 1 LAST PACK_TYPE 0402
J 0
(-1235 2525);
DISPLAY 0.617021 (-1235 2525);
PAINT SKYBLUE (-1235 2525);
FORCEPROP 1 LAST MATERIAL CHIP
J 0
(-1235 2625);
DISPLAY 0.617021 (-1235 2625);
PAINT SKYBLUE (-1235 2625);
FORCEPROP 1 LAST WATTAGE 1/16W
J 0
(-1235 2675);
DISPLAY 0.617021 (-1235 2675);
PAINT SKYBLUE (-1235 2675);
FORCEPROP 1 LASTPIN (-1275 2600) $PN 2
J 0
(-1270 2610);
DISPLAY 0.617021 (-1270 2610);
PAINT ORANGE (-1270 2610);
FORCEPROP 1 LASTPIN (-1275 2800) $PN 1
J 0
(-1270 2762);
DISPLAY 0.617021 (-1270 2762);
PAINT ORANGE (-1270 2762);
FORCEPROP 2 LAST CDS_LIB mstr_discrete
J 2
(-1275 2700);
PAINT ORANGE (-1275 2700);
DISPLAY INVISIBLE (-1275 2700);
FORCEPROP 2 LAST SEC_TYPE 0402
J 0
(-1225 2925);
DISPLAY 1.021277 (-1225 2925);
PAINT ORANGE (-1225 2925);
DISPLAY INVISIBLE (-1225 2925);
FORCEPROP 2 LAST BOM_COST PROC_SIDEBAND
J 0
(-1275 2700);
PAINT WHITE (-1275 2700);
DISPLAY INVISIBLE (-1275 2700);
FORCEPROP 2 LAST SEC 1
J 0
(-1225 2925);
DISPLAY 0.680851 (-1225 2925);
PAINT MONO (-1225 2925);
DISPLAY INVISIBLE (-1225 2925);
FORCEPROP 2 LAST CDS_LOCATION R5N4
J 0
(-1230 2825);
DISPLAY 0.617021 (-1230 2825);
PAINT AQUA (-1230 2825);
DISPLAY INVISIBLE (-1230 2825);
FORCEPROP 1 LAST PATH I241
J 0
(-1225 2875);
DISPLAY 0.978723 (-1225 2875);
PAINT WHITE (-1225 2875);
DISPLAY INVISIBLE (-1225 2875);
FORCEPROP 2 LAST ROOM CPU0
J 0
(-1250 2475);
PAINT WHITE (-1250 2475);
DISPLAY INVISIBLE (-1250 2475);
FORCEADD P3V3_STBY..1
(-1075 1725);
FORCEPROP 3 LASTPIN (-1075 1675) SIG_NAME P3V3_STBY\g
J 0
(-1065 1685);
DISPLAY 0.659574 (-1065 1685);
PAINT MONO (-1065 1685);
DISPLAY INVISIBLE (-1065 1685);
FORCEPROP 1 LAST VOLTAGE 3.3V
J 0
(-1120 1682);
DISPLAY 0.340426 (-1120 1682);
PAINT SKYBLUE (-1120 1682);
DISPLAY INVISIBLE (-1120 1682);
FORCEPROP 2 LAST CDS_LIB mstr_symbols
J 0
(-1075 1725);
PAINT ORANGE (-1075 1725);
DISPLAY INVISIBLE (-1075 1725);
FORCEPROP 1 LAST SIZE 1B
J 0
(-1030 1747);
DISPLAY 0.340426 (-1030 1747);
PAINT GREEN (-1030 1747);
DISPLAY INVISIBLE (-1030 1747);
FORCEPROP 1 LAST PATH I243
J 0
(-1030 1727);
DISPLAY 0.340426 (-1030 1727);
PAINT GREEN (-1030 1727);
DISPLAY INVISIBLE (-1030 1727);
FORCEPROP 1 LAST BODY_TYPE PLUMBING
J 0
(-1120 1682);
DISPLAY 0.340426 (-1120 1682);
PAINT GREEN (-1120 1682);
DISPLAY INVISIBLE (-1120 1682);
FORCEPROP 1 LAST HDL_POWER P3V3_STBY
J 0
(-1375 1600);
DISPLAY 0.872340 (-1375 1600);
PAINT GREEN (-1375 1600);
DISPLAY INVISIBLE (-1375 1600);
FORCEADD RES..1
(-2450 4250);
FORCEPROP 1 LAST LOCATION R4P18
J 0
(-2500 4275);
DISPLAY 0.617021 (-2500 4275);
PAINT AQUA (-2500 4275);
FORCEPROP 1 LAST PART_NUMBER G21796-047
J 0
(-2300 4100);
DISPLAY 0.617021 (-2300 4100);
PAINT BLUE (-2300 4100);
FORCEPROP 1 LAST VALUE 49.9
J 2
(-2675 4150);
DISPLAY 0.617021 (-2675 4150);
PAINT SKYBLUE (-2675 4150);
FORCEPROP 1 LAST TOLERANCE 1%
J 0
(-2675 4150);
DISPLAY 0.617021 (-2675 4150);
PAINT SKYBLUE (-2675 4150);
FORCEPROP 1 LAST PACK_TYPE 0402
J 0
(-2900 4150);
DISPLAY 0.617021 (-2900 4150);
PAINT SKYBLUE (-2900 4150);
FORCEPROP 1 LAST MATERIAL CHIP
J 0
(-2475 4125);
DISPLAY 0.617021 (-2475 4125);
PAINT SKYBLUE (-2475 4125);
FORCEPROP 1 LAST WATTAGE 1/16W
J 2
(-2925 4150);
DISPLAY 0.617021 (-2925 4150);
PAINT SKYBLUE (-2925 4150);
FORCEPROP 1 LASTPIN (-2350 4250) $PN 2
J 0
(-2388 4262);
DISPLAY 0.617021 (-2388 4262);
PAINT ORANGE (-2388 4262);
FORCEPROP 1 LASTPIN (-2550 4250) $PN 1
J 0
(-2538 4262);
DISPLAY 0.617021 (-2538 4262);
PAINT ORANGE (-2538 4262);
FORCEPROP 2 LAST SEC_TYPE 0402
J 0
(-2500 4450);
DISPLAY 1.021277 (-2500 4450);
PAINT ORANGE (-2500 4450);
DISPLAY INVISIBLE (-2500 4450);
FORCEPROP 2 LAST CDS_LIB mstr_discrete
J 0
(-2450 4250);
PAINT ORANGE (-2450 4250);
DISPLAY INVISIBLE (-2450 4250);
FORCEPROP 0 LAST BOM_COST PROC_SIDEBAND
J 0
(-2500 4375);
DISPLAY 1.021277 (-2500 4375);
PAINT ORANGE (-2500 4375);
DISPLAY INVISIBLE (-2500 4375);
FORCEPROP 2 LAST SEC 1
J 0
(-2500 4450);
DISPLAY 0.680851 (-2500 4450);
PAINT MONO (-2500 4450);
DISPLAY INVISIBLE (-2500 4450);
FORCEPROP 2 LAST CDS_LOCATION R4P18
J 0
(-2500 4275);
DISPLAY 0.617021 (-2500 4275);
PAINT AQUA (-2500 4275);
DISPLAY INVISIBLE (-2500 4275);
FORCEPROP 1 LAST PATH I244
J 0
(-2500 4400);
DISPLAY 0.978723 (-2500 4400);
PAINT WHITE (-2500 4400);
DISPLAY INVISIBLE (-2500 4400);
FORCEPROP 0 LAST ROOM CPU0
J 0
(-2500 4375);
DISPLAY 1.021277 (-2500 4375);
PAINT ORANGE (-2500 4375);
DISPLAY INVISIBLE (-2500 4375);
FORCEADD OFFPAGE..1
R 2
(-1800 1650);
FORCEPROP 2 LAST $XR0 90 
J 0
(-1614 1650);
DISPLAY 0.638298 (-1614 1650);
PAINT MONO (-1614 1650);
FORCEPROP 2 LAST CDS_LIB mstr_standard
J 0
(-1800 1650);
PAINT MONO (-1800 1650);
DISPLAY INVISIBLE (-1800 1650);
FORCEPROP 2 LAST PATH I247
J 0
(-1600 1700);
DISPLAY 1.021277 (-1600 1700);
PAINT ORANGE (-1600 1700);
DISPLAY INVISIBLE (-1600 1700);
FORCEPROP 1 LAST OFFPAGE TRUE
J 2
(-2125 1525);
DISPLAY 0.872340 (-2125 1525);
PAINT GREEN (-2125 1525);
DISPLAY INVISIBLE (-2125 1525);
FORCEPROP 1 LAST COMMENT_BODY TRUE
J 2
(-1925 1550);
DISPLAY 0.872340 (-1925 1550);
PAINT GREEN (-1925 1550);
DISPLAY INVISIBLE (-1925 1550);
FORCEADD OFFPAGE..1
R 2
(-1800 1600);
FORCEPROP 2 LAST $XR0 90 
J 0
(-1614 1600);
DISPLAY 0.638298 (-1614 1600);
PAINT MONO (-1614 1600);
FORCEPROP 2 LAST CDS_LIB mstr_standard
J 0
(-1800 1600);
PAINT ORANGE (-1800 1600);
DISPLAY INVISIBLE (-1800 1600);
FORCEPROP 2 LAST PATH I254
J 0
(-1625 1675);
DISPLAY 1.021277 (-1625 1675);
PAINT ORANGE (-1625 1675);
DISPLAY INVISIBLE (-1625 1675);
FORCEPROP 1 LAST OFFPAGE TRUE
J 2
(-2125 1475);
DISPLAY 0.872340 (-2125 1475);
PAINT GREEN (-2125 1475);
DISPLAY INVISIBLE (-2125 1475);
FORCEPROP 1 LAST COMMENT_BODY TRUE
J 2
(-1925 1500);
DISPLAY 0.872340 (-1925 1500);
PAINT GREEN (-1925 1500);
DISPLAY INVISIBLE (-1925 1500);
FORCEADD OFFPAGE..1
R 2
(-1800 1550);
FORCEPROP 2 LAST $XR0 90 
J 0
(-1614 1550);
DISPLAY 0.638298 (-1614 1550);
PAINT MONO (-1614 1550);
FORCEPROP 2 LAST CDS_LIB mstr_standard
J 0
(-1800 1550);
PAINT ORANGE (-1800 1550);
DISPLAY INVISIBLE (-1800 1550);
FORCEPROP 2 LAST PATH I255
J 0
(-1625 1625);
DISPLAY 1.021277 (-1625 1625);
PAINT ORANGE (-1625 1625);
DISPLAY INVISIBLE (-1625 1625);
FORCEPROP 1 LAST OFFPAGE TRUE
J 2
(-2125 1425);
DISPLAY 0.872340 (-2125 1425);
PAINT GREEN (-2125 1425);
DISPLAY INVISIBLE (-2125 1425);
FORCEPROP 1 LAST COMMENT_BODY TRUE
J 2
(-1925 1450);
DISPLAY 0.872340 (-1925 1450);
PAINT GREEN (-1925 1450);
DISPLAY INVISIBLE (-1925 1450);
FORCEADD OFFPAGE..1
R 2
(-1800 1500);
FORCEPROP 2 LAST $XR0 90 
J 0
(-1614 1500);
DISPLAY 0.638298 (-1614 1500);
PAINT MONO (-1614 1500);
FORCEPROP 2 LAST CDS_LIB mstr_standard
J 0
(-1800 1500);
PAINT ORANGE (-1800 1500);
DISPLAY INVISIBLE (-1800 1500);
FORCEPROP 2 LAST PATH I256
J 0
(-1625 1575);
DISPLAY 1.021277 (-1625 1575);
PAINT ORANGE (-1625 1575);
DISPLAY INVISIBLE (-1625 1575);
FORCEPROP 1 LAST OFFPAGE TRUE
J 2
(-2125 1375);
DISPLAY 0.872340 (-2125 1375);
PAINT GREEN (-2125 1375);
DISPLAY INVISIBLE (-2125 1375);
FORCEPROP 1 LAST COMMENT_BODY TRUE
J 2
(-1925 1400);
DISPLAY 0.872340 (-1925 1400);
PAINT GREEN (-1925 1400);
DISPLAY INVISIBLE (-1925 1400);
FORCEADD PVCCIO_CPU0..1
(-650 3375);
FORCEPROP 3 LASTPIN (-650 3325) SIG_NAME PVCCIO_CPU0\g
J 0
(-640 3335);
DISPLAY 0.659574 (-640 3335);
PAINT MONO (-640 3335);
DISPLAY INVISIBLE (-640 3335);
FORCEPROP 1 LAST VOLTAGE 1.1V
J 0
(-695 3332);
DISPLAY 0.340426 (-695 3332);
PAINT SKYBLUE (-695 3332);
DISPLAY INVISIBLE (-695 3332);
FORCEPROP 2 LAST CDS_LIB mstr_symbols
J 0
(-650 3375);
PAINT ORANGE (-650 3375);
DISPLAY INVISIBLE (-650 3375);
FORCEPROP 1 LAST PATH I257
J 0
(-600 3400);
DISPLAY 0.872340 (-600 3400);
PAINT AQUA (-600 3400);
DISPLAY INVISIBLE (-600 3400);
FORCEPROP 1 LAST BODY_TYPE PLUMBING
J 0
(-695 3332);
DISPLAY 0.340426 (-695 3332);
PAINT GREEN (-695 3332);
DISPLAY INVISIBLE (-695 3332);
FORCEPROP 1 LAST HDL_POWER PVCCIO_CPU0
J 1
(-650 3425);
DISPLAY 0.872340 (-650 3425);
PAINT GREEN (-650 3425);
DISPLAY INVISIBLE (-650 3425);
FORCEADD RES..2
(-1075 1450);
FORCEPROP 1 LAST VALUE 4.75K
J 0
(-1030 1525);
DISPLAY 0.617021 (-1030 1525);
PAINT SKYBLUE (-1030 1525);
FORCEPROP 1 LAST TOLERANCE 1%
J 0
(-1030 1475);
DISPLAY 0.617021 (-1030 1475);
PAINT SKYBLUE (-1030 1475);
FORCEPROP 1 LAST WATTAGE 1/16W
J 0
(-1035 1425);
DISPLAY 0.617021 (-1035 1425);
PAINT SKYBLUE (-1035 1425);
FORCEPROP 1 LASTPIN (-1075 1550) $PN 1
J 0
(-1070 1512);
DISPLAY 0.617021 (-1070 1512);
PAINT ORANGE (-1070 1512);
FORCEPROP 1 LASTPIN (-1075 1350) $PN 2
J 0
(-1070 1360);
DISPLAY 0.617021 (-1070 1360);
PAINT ORANGE (-1070 1360);
FORCEPROP 1 LAST PACK_TYPE 0402
J 0
(-1035 1275);
DISPLAY 0.617021 (-1035 1275);
PAINT SKYBLUE (-1035 1275);
FORCEPROP 1 LAST LOCATION R4R5
J 0
(-1030 1575);
DISPLAY 0.617021 (-1030 1575);
PAINT AQUA (-1030 1575);
FORCEPROP 1 LAST MATERIAL CHIP
J 0
(-1035 1375);
DISPLAY 0.617021 (-1035 1375);
PAINT SKYBLUE (-1035 1375);
FORCEPROP 1 LAST PART_NUMBER G21796-072
J 0
(-1035 1325);
DISPLAY 0.617021 (-1035 1325);
PAINT BLUE (-1035 1325);
FORCEPROP 2 LAST CDS_LIB mstr_discrete
J 0
(-1075 1450);
PAINT ORANGE (-1075 1450);
DISPLAY INVISIBLE (-1075 1450);
FORCEPROP 2 LAST SEC_TYPE 0402
J 0
(-1025 1675);
DISPLAY 1.021277 (-1025 1675);
PAINT ORANGE (-1025 1675);
DISPLAY INVISIBLE (-1025 1675);
FORCEPROP 2 LAST SEC 1
J 0
(-1025 1675);
DISPLAY 0.680851 (-1025 1675);
PAINT MONO (-1025 1675);
DISPLAY INVISIBLE (-1025 1675);
FORCEPROP 2 LAST CDS_LOCATION R4R5
J 0
(-1030 1575);
DISPLAY 0.617021 (-1030 1575);
PAINT AQUA (-1030 1575);
DISPLAY INVISIBLE (-1030 1575);
FORCEPROP 1 LAST PATH I258
J 0
(-1025 1625);
DISPLAY 0.978723 (-1025 1625);
PAINT WHITE (-1025 1625);
DISPLAY INVISIBLE (-1025 1625);
FORCEPROP 0 LAST ROOM CPU0
J 0
(-1025 1675);
DISPLAY 1.021277 (-1025 1675);
PAINT ORANGE (-1025 1675);
DISPLAY INVISIBLE (-1025 1675);
FORCEADD SKX_EXT_B..1
(-4075 2850);
FORCEPROP 1 LAST LOCATION U5D1
J 0
(-4975 4750);
DISPLAY 0.617021 (-4975 4750);
PAINT AQUA (-4975 4750);
FORCEPROP 1 LAST PART_NUMBER TBD
J 0
(-4975 950);
DISPLAY 0.617021 (-4975 950);
PAINT BLUE (-4975 950);
FORCEPROP 1 LAST MATERIAL IC
J 0
(-4975 4700);
DISPLAY 0.617021 (-4975 4700);
PAINT SKYBLUE (-4975 4700);
FORCEPROP 2 LASTPIN (-5025 2050) $PN CK29
J 2
(-5035 2060);
DISPLAY 0.617021 (-5035 2060);
PAINT ORANGE (-5035 2060);
FORCEPROP 2 LASTPIN (-5025 2000) $PN CL28
J 2
(-5035 2010);
DISPLAY 0.617021 (-5035 2010);
PAINT ORANGE (-5035 2010);
FORCEPROP 2 LASTPIN (-5025 2150) $PN AP29
J 2
(-5035 2160);
DISPLAY 0.617021 (-5035 2160);
PAINT ORANGE (-5035 2160);
FORCEPROP 2 LASTPIN (-5025 2100) $PN AT29
J 2
(-5035 2110);
DISPLAY 0.617021 (-5035 2110);
PAINT ORANGE (-5035 2110);
FORCEPROP 2 LASTPIN (-3125 2850) $PN AV15
J 0
(-3115 2860);
DISPLAY 0.617021 (-3115 2860);
PAINT ORANGE (-3115 2860);
FORCEPROP 2 LASTPIN (-3125 2900) $PN AW18
J 0
(-3115 2910);
DISPLAY 0.617021 (-3115 2910);
PAINT ORANGE (-3115 2910);
FORCEPROP 2 LASTPIN (-3125 2100) $PN AM11
J 0
(-3115 2110);
DISPLAY 0.617021 (-3115 2110);
PAINT ORANGE (-3115 2110);
FORCEPROP 2 LASTPIN (-5025 1200) $PN Y13
J 2
(-5035 1210);
DISPLAY 0.617021 (-5035 1210);
PAINT ORANGE (-5035 1210);
FORCEPROP 2 LASTPIN (-5025 1250) $PN W14
J 2
(-5035 1260);
DISPLAY 0.617021 (-5035 1260);
PAINT ORANGE (-5035 1260);
FORCEPROP 2 LASTPIN (-3125 3150) $PN AB15
J 0
(-3115 3160);
DISPLAY 0.617021 (-3115 3160);
PAINT ORANGE (-3115 3160);
FORCEPROP 2 LASTPIN (-3125 1650) $PN AW14
J 0
(-3115 1660);
DISPLAY 0.617021 (-3115 1660);
PAINT ORANGE (-3115 1660);
FORCEPROP 2 LASTPIN (-3125 1550) $PN DB51
J 0
(-3115 1560);
DISPLAY 0.617021 (-3115 1560);
PAINT ORANGE (-3115 1560);
FORCEPROP 2 LASTPIN (-3125 1500) $PN AY19
J 0
(-3115 1510);
DISPLAY 0.617021 (-3115 1510);
PAINT ORANGE (-3115 1510);
FORCEPROP 2 LASTPIN (-3125 1150) $PN AE14
J 0
(-3115 1160);
DISPLAY 0.617021 (-3115 1160);
PAINT ORANGE (-3115 1160);
FORCEPROP 2 LASTPIN (-5025 1350) $PN AC14
J 2
(-5035 1360);
DISPLAY 0.617021 (-5035 1360);
PAINT ORANGE (-5035 1360);
FORCEPROP 2 LASTPIN (-5025 1300) $PN AA14
J 2
(-5035 1310);
DISPLAY 0.617021 (-5035 1310);
PAINT ORANGE (-5035 1310);
FORCEPROP 2 LASTPIN (-3125 4000) $PN DJ44
J 0
(-3115 4010);
DISPLAY 0.617021 (-3115 4010);
PAINT ORANGE (-3115 4010);
FORCEPROP 2 LASTPIN (-3125 3850) $PN DB45
J 0
(-3115 3860);
DISPLAY 0.617021 (-3115 3860);
PAINT ORANGE (-3115 3860);
FORCEPROP 2 LASTPIN (-3125 3950) $PN DG44
J 0
(-3115 3960);
DISPLAY 0.617021 (-3115 3960);
PAINT ORANGE (-3115 3960);
FORCEPROP 2 LASTPIN (-3125 3800) $PN DC44
J 0
(-3115 3810);
DISPLAY 0.617021 (-3115 3810);
PAINT ORANGE (-3115 3810);
FORCEPROP 2 LASTPIN (-3125 3900) $PN DL44
J 0
(-3115 3910);
DISPLAY 0.617021 (-3115 3910);
PAINT ORANGE (-3115 3910);
FORCEPROP 2 LASTPIN (-3125 3750) $PN DE44
J 0
(-3115 3760);
DISPLAY 0.617021 (-3115 3760);
PAINT ORANGE (-3115 3760);
FORCEPROP 2 LASTPIN (-3125 2550) $PN AU20
J 0
(-3115 2560);
DISPLAY 0.617021 (-3115 2560);
PAINT ORANGE (-3115 2560);
FORCEPROP 2 LASTPIN (-3125 2650) $PN AU16
J 0
(-3115 2660);
DISPLAY 0.617021 (-3115 2660);
PAINT ORANGE (-3115 2660);
FORCEPROP 2 LASTPIN (-3125 2600) $PN AU22
J 0
(-3115 2610);
DISPLAY 0.617021 (-3115 2610);
PAINT ORANGE (-3115 2610);
FORCEPROP 2 LASTPIN (-5025 2450) $PN CW58
J 2
(-5035 2460);
DISPLAY 0.617021 (-5035 2460);
PAINT ORANGE (-5035 2460);
FORCEPROP 2 LASTPIN (-5025 2500) $PN CT59
J 2
(-5035 2510);
DISPLAY 0.617021 (-5035 2510);
PAINT ORANGE (-5035 2510);
FORCEPROP 2 LASTPIN (-3125 2050) $PN CV59
J 0
(-3115 2060);
DISPLAY 0.617021 (-3115 2060);
PAINT ORANGE (-3115 2060);
FORCEPROP 2 LASTPIN (-3125 1250) $PN AB13
J 0
(-3115 1260);
DISPLAY 0.617021 (-3115 1260);
PAINT ORANGE (-3115 1260);
FORCEPROP 2 LASTPIN (-3125 3050) $PN AR18
J 0
(-3115 3060);
DISPLAY 0.617021 (-3115 3060);
PAINT ORANGE (-3115 3060);
FORCEPROP 2 LASTPIN (-3125 4450) $PN AP21
J 0
(-3115 4460);
DISPLAY 0.617021 (-3115 4460);
PAINT ORANGE (-3115 4460);
FORCEPROP 2 LASTPIN (-3125 4500) $PN BC24
J 0
(-3115 4510);
DISPLAY 0.617021 (-3115 4510);
PAINT ORANGE (-3115 4510);
FORCEPROP 2 LASTPIN (-3125 3200) $PN AC16
J 0
(-3115 3210);
DISPLAY 0.617021 (-3115 3210);
PAINT ORANGE (-3115 3210);
FORCEPROP 2 LASTPIN (-3125 3250) $PN AB17
J 0
(-3115 3260);
DISPLAY 0.617021 (-3115 3260);
PAINT ORANGE (-3115 3260);
FORCEPROP 2 LASTPIN (-3125 2450) $PN DB71
J 0
(-3115 2460);
DISPLAY 0.617021 (-3115 2460);
PAINT ORANGE (-3115 2460);
FORCEPROP 2 LASTPIN (-3125 2400) $PN CY71
J 0
(-3115 2410);
DISPLAY 0.617021 (-3115 2410);
PAINT ORANGE (-3115 2410);
FORCEPROP 2 LASTPIN (-3125 1400) $PN AR12
J 0
(-3115 1410);
DISPLAY 0.617021 (-3115 1410);
PAINT ORANGE (-3115 1410);
FORCEPROP 2 LASTPIN (-3125 1350) $PN AG16
J 0
(-3115 1360);
DISPLAY 0.617021 (-3115 1360);
PAINT ORANGE (-3115 1360);
FORCEPROP 2 LASTPIN (-3125 4200) $PN AT19
J 0
(-3115 4210);
DISPLAY 0.617021 (-3115 4210);
PAINT ORANGE (-3115 4210);
FORCEPROP 2 LASTPIN (-3125 4250) $PN AR14
J 0
(-3115 4260);
DISPLAY 0.617021 (-3115 4260);
PAINT ORANGE (-3115 4260);
FORCEPROP 2 LASTPIN (-3125 2750) $PN AF15
J 0
(-3115 2760);
DISPLAY 0.617021 (-3115 2760);
PAINT ORANGE (-3115 2760);
FORCEPROP 2 LASTPIN (-3125 2300) $PN DA72
J 0
(-3115 2310);
DISPLAY 0.617021 (-3115 2310);
PAINT ORANGE (-3115 2310);
FORCEPROP 2 LASTPIN (-3125 2250) $PN CW72
J 0
(-3115 2260);
DISPLAY 0.617021 (-3115 2260);
PAINT ORANGE (-3115 2260);
FORCEPROP 2 LASTPIN (-3125 2200) $PN DC72
J 0
(-3115 2210);
DISPLAY 0.617021 (-3115 2210);
PAINT ORANGE (-3115 2210);
FORCEPROP 2 LASTPIN (-3125 1800) $PN CW56
J 0
(-3115 1810);
DISPLAY 0.617021 (-3115 1810);
PAINT ORANGE (-3115 1810);
FORCEPROP 2 LASTPIN (-3125 1700) $PN CU58
J 0
(-3115 1710);
DISPLAY 0.617021 (-3115 1710);
PAINT ORANGE (-3115 1710);
FORCEPROP 2 LASTPIN (-3125 4100) $PN AU12
J 0
(-3115 4110);
DISPLAY 0.617021 (-3115 4110);
PAINT ORANGE (-3115 4110);
FORCEPROP 2 LASTPIN (-5025 2600) $PN AL18
J 2
(-5035 2610);
DISPLAY 0.617021 (-5035 2610);
PAINT ORANGE (-5035 2610);
FORCEPROP 2 LASTPIN (-5025 2650) $PN AM19
J 2
(-5035 2660);
DISPLAY 0.617021 (-5035 2660);
PAINT ORANGE (-5035 2660);
FORCEPROP 2 LASTPIN (-5025 2250) $PN CL30
J 2
(-5035 2260);
DISPLAY 0.617021 (-5035 2260);
PAINT ORANGE (-5035 2260);
FORCEPROP 2 LASTPIN (-5025 2200) $PN CN30
J 2
(-5035 2210);
DISPLAY 0.617021 (-5035 2210);
PAINT ORANGE (-5035 2210);
FORCEPROP 2 LASTPIN (-5025 2350) $PN CR30
J 2
(-5035 2360);
DISPLAY 0.617021 (-5035 2360);
PAINT ORANGE (-5035 2360);
FORCEPROP 2 LASTPIN (-5025 2300) $PN CP29
J 2
(-5035 2310);
DISPLAY 0.617021 (-5035 2310);
PAINT ORANGE (-5035 2310);
FORCEPROP 2 LASTPIN (-3125 1950) $PN AP11
J 0
(-3115 1960);
DISPLAY 0.617021 (-3115 1960);
PAINT ORANGE (-3115 1960);
FORCEPROP 2 LASTPIN (-3125 3350) $PN AN20
J 0
(-3115 3360);
DISPLAY 0.617021 (-3115 3360);
PAINT ORANGE (-3115 3360);
FORCEPROP 2 LASTPIN (-5025 3700) $PN AF13
J 2
(-5035 3710);
DISPLAY 0.617021 (-5035 3710);
PAINT ORANGE (-5035 3710);
FORCEPROP 2 LASTPIN (-5025 3750) $PN AH13
J 2
(-5035 3760);
DISPLAY 0.617021 (-5035 3760);
PAINT ORANGE (-5035 3760);
FORCEPROP 2 LASTPIN (-5025 1950) $PN CT31
J 2
(-5035 1960);
DISPLAY 0.617021 (-5035 1960);
PAINT ORANGE (-5035 1960);
FORCEPROP 2 LASTPIN (-5025 1900) $PN CU32
J 2
(-5035 1910);
DISPLAY 0.617021 (-5035 1910);
PAINT ORANGE (-5035 1910);
FORCEPROP 2 LASTPIN (-3125 1900) $PN AE20
J 0
(-3115 1910);
DISPLAY 0.617021 (-3115 1910);
PAINT ORANGE (-3115 1910);
FORCEPROP 2 LASTPIN (-3125 3000) $PN AV17
J 0
(-3115 3010);
DISPLAY 0.617021 (-3115 3010);
PAINT ORANGE (-3115 3010);
FORCEPROP 2 LASTPIN (-3125 3550) $PN AL12
J 0
(-3115 3560);
DISPLAY 0.617021 (-3115 3560);
PAINT ORANGE (-3115 3560);
FORCEPROP 2 LASTPIN (-3125 3500) $PN AK11
J 0
(-3115 3510);
DISPLAY 0.617021 (-3115 3510);
PAINT ORANGE (-3115 3510);
FORCEPROP 2 LASTPIN (-3125 3450) $PN AJ12
J 0
(-3115 3460);
DISPLAY 0.617021 (-3115 3460);
PAINT ORANGE (-3115 3460);
FORCEPROP 2 LASTPIN (-3125 4350) $PN AJ14
J 0
(-3115 4360);
DISPLAY 0.617021 (-3115 4360);
PAINT ORANGE (-3115 4360);
FORCEPROP 2 LASTPIN (-5025 2900) $PN AD17
J 2
(-5035 2910);
DISPLAY 0.617021 (-5035 2910);
PAINT ORANGE (-5035 2910);
FORCEPROP 2 LASTPIN (-5025 2800) $PN AE18
J 2
(-5035 2810);
DISPLAY 0.617021 (-5035 2810);
PAINT ORANGE (-5035 2810);
FORCEPROP 2 LASTPIN (-5025 3850) $PN DV63
J 2
(-5035 3860);
DISPLAY 0.617021 (-5035 3860);
PAINT ORANGE (-5035 3860);
FORCEPROP 2 LASTPIN (-5025 3100) $PN DD49
J 2
(-5035 3110);
DISPLAY 0.617021 (-5035 3110);
PAINT ORANGE (-5035 3110);
FORCEPROP 2 LASTPIN (-5025 3050) $PN DD47
J 2
(-5035 3060);
DISPLAY 0.617021 (-5035 3060);
PAINT ORANGE (-5035 3060);
FORCEPROP 2 LASTPIN (-5025 3000) $PN DC48
J 2
(-5035 3010);
DISPLAY 0.617021 (-5035 3010);
PAINT ORANGE (-5035 3010);
FORCEPROP 2 LASTPIN (-5025 4000) $PN CR28
J 2
(-5035 4010);
DISPLAY 0.617021 (-5035 4010);
PAINT ORANGE (-5035 4010);
FORCEPROP 2 LASTPIN (-5025 2850) $PN AF17
J 2
(-5035 2860);
DISPLAY 0.617021 (-5035 2860);
PAINT ORANGE (-5035 2860);
FORCEPROP 2 LASTPIN (-5025 2750) $PN AJ18
J 2
(-5035 2760);
DISPLAY 0.617021 (-5035 2760);
PAINT ORANGE (-5035 2760);
FORCEPROP 2 LASTPIN (-5025 3900) $PN U64
J 2
(-5035 3910);
DISPLAY 0.617021 (-5035 3910);
PAINT ORANGE (-5035 3910);
FORCEPROP 2 LASTPIN (-5025 3250) $PN AC42
J 2
(-5035 3260);
DISPLAY 0.617021 (-5035 3260);
PAINT ORANGE (-5035 3260);
FORCEPROP 2 LASTPIN (-5025 3200) $PN AB43
J 2
(-5035 3210);
DISPLAY 0.617021 (-5035 3210);
PAINT ORANGE (-5035 3210);
FORCEPROP 2 LASTPIN (-5025 3150) $PN Y43
J 2
(-5035 3160);
DISPLAY 0.617021 (-5035 3160);
PAINT ORANGE (-5035 3160);
FORCEPROP 2 LASTPIN (-5025 4050) $PN AN30
J 2
(-5035 4060);
DISPLAY 0.617021 (-5035 4060);
PAINT ORANGE (-5035 4060);
FORCEPROP 2 LASTPIN (-5025 3600) $PN CV61
J 2
(-5035 3610);
DISPLAY 0.617021 (-5035 3610);
PAINT ORANGE (-5035 3610);
FORCEPROP 2 LASTPIN (-5025 3550) $PN CT61
J 2
(-5035 3560);
DISPLAY 0.617021 (-5035 3560);
PAINT ORANGE (-5035 3560);
FORCEPROP 2 LASTPIN (-5025 3500) $PN CP61
J 2
(-5035 3510);
DISPLAY 0.617021 (-5035 3510);
PAINT ORANGE (-5035 3510);
FORCEPROP 2 LASTPIN (-5025 3450) $PN AH63
J 2
(-5035 3460);
DISPLAY 0.617021 (-5035 3460);
PAINT ORANGE (-5035 3460);
FORCEPROP 2 LASTPIN (-5025 3400) $PN AK63
J 2
(-5035 3410);
DISPLAY 0.617021 (-5035 3410);
PAINT ORANGE (-5035 3410);
FORCEPROP 2 LASTPIN (-5025 3350) $PN AJ64
J 2
(-5035 3360);
DISPLAY 0.617021 (-5035 3360);
PAINT ORANGE (-5035 3360);
FORCEPROP 2 LASTPIN (-3125 3650) $PN AL14
J 0
(-3115 3660);
DISPLAY 0.617021 (-3115 3660);
PAINT ORANGE (-3115 3660);
FORCEPROP 2 LASTPIN (-5025 1800) $PN AC12
J 2
(-5035 1810);
DISPLAY 0.617021 (-5035 1810);
PAINT ORANGE (-5035 1810);
FORCEPROP 2 LASTPIN (-5025 1750) $PN AE12
J 2
(-5035 1760);
DISPLAY 0.617021 (-5035 1760);
PAINT ORANGE (-5035 1760);
FORCEPROP 2 LASTPIN (-5025 1700) $PN Y11
J 2
(-5035 1710);
DISPLAY 0.617021 (-5035 1710);
PAINT ORANGE (-5035 1710);
FORCEPROP 2 LASTPIN (-5025 1650) $PN AA12
J 2
(-5035 1660);
DISPLAY 0.617021 (-5035 1660);
PAINT ORANGE (-5035 1660);
FORCEPROP 2 LASTPIN (-5025 1600) $PN AF11
J 2
(-5035 1610);
DISPLAY 0.617021 (-5035 1610);
PAINT ORANGE (-5035 1610);
FORCEPROP 2 LASTPIN (-5025 1550) $PN AG10
J 2
(-5035 1560);
DISPLAY 0.617021 (-5035 1560);
PAINT ORANGE (-5035 1560);
FORCEPROP 2 LASTPIN (-5025 1500) $PN AH11
J 2
(-5035 1510);
DISPLAY 0.617021 (-5035 1510);
PAINT ORANGE (-5035 1510);
FORCEPROP 2 LASTPIN (-5025 1450) $PN AJ10
J 2
(-5035 1460);
DISPLAY 0.617021 (-5035 1460);
PAINT ORANGE (-5035 1460);
FORCEPROP 2 LASTPIN (-3125 2950) $PN BD23
J 0
(-3115 2960);
DISPLAY 0.617021 (-3115 2960);
PAINT ORANGE (-3115 2960);
FORCEPROP 2 LASTPIN (-3125 2800) $PN BA20
J 0
(-3115 2810);
DISPLAY 0.617021 (-3115 2810);
PAINT ORANGE (-3115 2810);
FORCEPROP 2 LASTPIN (-5025 4200) $PN CU26
J 2
(-5035 4210);
DISPLAY 0.617021 (-5035 4210);
PAINT ORANGE (-5035 4210);
FORCEPROP 2 LASTPIN (-5025 4150) $PN CT25
J 2
(-5035 4160);
DISPLAY 0.617021 (-5035 4160);
PAINT ORANGE (-5035 4160);
FORCEPROP 2 LASTPIN (-5025 4350) $PN CP27
J 2
(-5035 4360);
DISPLAY 0.617021 (-5035 4360);
PAINT ORANGE (-5035 4360);
FORCEPROP 2 LASTPIN (-5025 4300) $PN CR26
J 2
(-5035 4310);
DISPLAY 0.617021 (-5035 4310);
PAINT ORANGE (-5035 4310);
FORCEPROP 2 LASTPIN (-5025 4500) $PN AW24
J 2
(-5035 4510);
DISPLAY 0.617021 (-5035 4510);
PAINT ORANGE (-5035 4510);
FORCEPROP 2 LASTPIN (-5025 4450) $PN AU24
J 2
(-5035 4460);
DISPLAY 0.617021 (-5035 4460);
PAINT ORANGE (-5035 4460);
FORCEPROP 2 LASTPIN (-3125 1600) $PN DC50
J 0
(-3115 1610);
DISPLAY 0.617021 (-3115 1610);
PAINT ORANGE (-3115 1610);
FORCEPROP 2 LASTPIN (-3125 1750) $PN CV57
J 0
(-3115 1760);
DISPLAY 0.617021 (-3115 1760);
PAINT ORANGE (-3115 1760);
FORCEPROP 1 LAST PACK_TYPE BGA1
J 0
(-4975 4800);
PAINT SKYBLUE (-4975 4800);
DISPLAY INVISIBLE (-4975 4800);
FORCEPROP 2 LAST CDS_LIB chpset_lib
J 0
(-4075 2850);
PAINT ORANGE (-4075 2850);
DISPLAY INVISIBLE (-4075 2850);
FORCEPROP 2 LAST SEC_TYPE BGA1
J 0
(-4975 4800);
DISPLAY 1.021277 (-4975 4800);
PAINT ORANGE (-4975 4800);
DISPLAY INVISIBLE (-4975 4800);
FORCEPROP 2 LAST SEC 1
J 0
(-4975 4800);
DISPLAY 0.680851 (-4975 4800);
PAINT MONO (-4975 4800);
DISPLAY INVISIBLE (-4975 4800);
FORCEPROP 2 LAST CDS_LOCATION U5D1
J 0
(-4975 4750);
DISPLAY 0.617021 (-4975 4750);
PAINT AQUA (-4975 4750);
DISPLAY INVISIBLE (-4975 4750);
FORCEPROP 1 LAST PATH I259
J 0
(-4075 4700);
PAINT GREEN (-4075 4700);
DISPLAY INVISIBLE (-4075 4700);
FORCEPROP 0 LAST ROOM CPU0
J 0
(-4975 4850);
DISPLAY 1.021277 (-4975 4850);
PAINT ORANGE (-4975 4850);
DISPLAY INVISIBLE (-4975 4850);
FORCEADD OFFPAGE..3
R 2
(-6375 1750);
FORCEPROP 2 LAST $XR0 55 
J 0
(-6624 1750);
DISPLAY 0.638298 (-6624 1750);
PAINT MONO (-6624 1750);
FORCEPROP 2 LAST $XR1 112 
J 0
(-6744 1750);
DISPLAY 0.638298 (-6744 1750);
PAINT MONO (-6744 1750);
FORCEPROP 2 LAST CDS_LIB mstr_standard
J 0
(-6375 1750);
PAINT ORANGE (-6375 1750);
DISPLAY INVISIBLE (-6375 1750);
FORCEPROP 2 LAST PATH I260
J 0
(-6325 1825);
DISPLAY 1.021277 (-6325 1825);
PAINT ORANGE (-6325 1825);
DISPLAY INVISIBLE (-6325 1825);
FORCEPROP 1 LAST OFFPAGE TRUE
J 2
(-6700 1625);
DISPLAY 0.872340 (-6700 1625);
PAINT GREEN (-6700 1625);
DISPLAY INVISIBLE (-6700 1625);
FORCEPROP 1 LAST COMMENT_BODY TRUE
J 2
(-6325 1650);
DISPLAY 0.872340 (-6325 1650);
PAINT GREEN (-6325 1650);
DISPLAY INVISIBLE (-6325 1650);
FORCEADD OFFPAGE..1
R 2
(-1825 1400);
FORCEPROP 2 LAST $XR0 112 
J 0
(-1639 1400);
DISPLAY 0.638298 (-1639 1400);
PAINT MONO (-1639 1400);
FORCEPROP 2 LAST $XR1 55 
J 0
(-1519 1400);
DISPLAY 0.638298 (-1519 1400);
PAINT MONO (-1519 1400);
FORCEPROP 2 LAST CDS_LIB mstr_standard
J 0
(-1825 1400);
PAINT ORANGE (-1825 1400);
DISPLAY INVISIBLE (-1825 1400);
FORCEPROP 2 LAST PATH I261
J 0
(-1650 1475);
DISPLAY 1.021277 (-1650 1475);
PAINT ORANGE (-1650 1475);
DISPLAY INVISIBLE (-1650 1475);
FORCEPROP 1 LAST OFFPAGE TRUE
J 2
(-2150 1275);
DISPLAY 0.872340 (-2150 1275);
PAINT GREEN (-2150 1275);
DISPLAY INVISIBLE (-2150 1275);
FORCEPROP 1 LAST COMMENT_BODY TRUE
J 2
(-1950 1300);
DISPLAY 0.872340 (-1950 1300);
PAINT GREEN (-1950 1300);
DISPLAY INVISIBLE (-1950 1300);
FORCEADD OFFPAGE..2
(-1825 1350);
FORCEPROP 2 LAST $XR0 55 
J 0
(-1636 1350);
DISPLAY 0.638298 (-1636 1350);
PAINT MONO (-1636 1350);
FORCEPROP 2 LAST $XR1 112 
J 0
(-1546 1350);
DISPLAY 0.638298 (-1546 1350);
PAINT MONO (-1546 1350);
FORCEPROP 2 LAST CDS_LIB mstr_standard
J 0
(-1825 1350);
PAINT ORANGE (-1825 1350);
DISPLAY INVISIBLE (-1825 1350);
FORCEPROP 2 LAST PATH I262
J 0
(-1650 1425);
DISPLAY 1.021277 (-1650 1425);
PAINT ORANGE (-1650 1425);
DISPLAY INVISIBLE (-1650 1425);
FORCEPROP 1 LAST OFFPAGE TRUE
J 0
(-1500 1225);
DISPLAY 1.170213 (-1500 1225);
PAINT GREEN (-1500 1225);
DISPLAY INVISIBLE (-1500 1225);
FORCEPROP 1 LAST COMMENT_BODY TRUE
J 0
(-1870 1255);
DISPLAY 1.170213 (-1870 1255);
PAINT PEACH (-1870 1255);
DISPLAY INVISIBLE (-1870 1255);
FORCEADD OFFPAGE..1
(-6325 2500);
FORCEPROP 2 LAST $XR0 156 
J 0
(-6607 2500);
DISPLAY 0.638298 (-6607 2500);
PAINT MONO (-6607 2500);
FORCEPROP 2 LAST CDS_LIB mstr_standard
J 0
(-6325 2500);
PAINT ORANGE (-6325 2500);
DISPLAY INVISIBLE (-6325 2500);
FORCEPROP 2 LAST PATH I263
J 0
(-6275 2575);
DISPLAY 1.021277 (-6275 2575);
PAINT ORANGE (-6275 2575);
DISPLAY INVISIBLE (-6275 2575);
FORCEPROP 1 LAST OFFPAGE TRUE
J 0
(-6000 2375);
DISPLAY 0.872340 (-6000 2375);
PAINT GREEN (-6000 2375);
DISPLAY INVISIBLE (-6000 2375);
FORCEPROP 1 LAST COMMENT_BODY TRUE
J 0
(-6200 2400);
DISPLAY 0.872340 (-6200 2400);
PAINT GREEN (-6200 2400);
DISPLAY INVISIBLE (-6200 2400);
FORCEADD OFFPAGE..6
(-6325 2450);
FORCEPROP 2 LAST $XR0 156 
J 0
(-6605 2450);
DISPLAY 0.638298 (-6605 2450);
PAINT MONO (-6605 2450);
FORCEPROP 2 LAST CDS_LIB mstr_standard
J 0
(-6325 2450);
PAINT ORANGE (-6325 2450);
DISPLAY INVISIBLE (-6325 2450);
FORCEPROP 2 LAST PATH I264
J 0
(-6275 2525);
DISPLAY 1.021277 (-6275 2525);
PAINT ORANGE (-6275 2525);
DISPLAY INVISIBLE (-6275 2525);
FORCEPROP 1 LAST OFFPAGE TRUE
J 0
(-6000 2325);
DISPLAY 0.872340 (-6000 2325);
PAINT GREEN (-6000 2325);
DISPLAY INVISIBLE (-6000 2325);
FORCEPROP 1 LAST COMMENT_BODY TRUE
J 0
(-6225 2375);
DISPLAY 0.872340 (-6225 2375);
PAINT GREEN (-6225 2375);
DISPLAY INVISIBLE (-6225 2375);
FORCEADD OFFPAGE..4
(-1800 2050);
FORCEPROP 2 LAST $XR0 156 
J 0
(-1614 2050);
DISPLAY 0.638298 (-1614 2050);
PAINT MONO (-1614 2050);
FORCEPROP 2 LAST CDS_LIB mstr_standard
J 0
(-1800 2050);
PAINT ORANGE (-1800 2050);
DISPLAY INVISIBLE (-1800 2050);
FORCEPROP 2 LAST PATH I265
J 0
(-1750 2125);
DISPLAY 1.021277 (-1750 2125);
PAINT ORANGE (-1750 2125);
DISPLAY INVISIBLE (-1750 2125);
FORCEPROP 1 LAST OFFPAGE TRUE
J 0
(-1475 1925);
DISPLAY 0.872340 (-1475 1925);
PAINT GREEN (-1475 1925);
DISPLAY INVISIBLE (-1475 1925);
FORCEPROP 1 LAST COMMENT_BODY TRUE
J 0
(-1825 1950);
DISPLAY 0.872340 (-1825 1950);
PAINT GREEN (-1825 1950);
DISPLAY INVISIBLE (-1825 1950);
FORCEADD OFFPAGE..4
(-1800 1800);
FORCEPROP 2 LAST $XR0 156 
J 0
(-1614 1800);
DISPLAY 0.638298 (-1614 1800);
PAINT MONO (-1614 1800);
FORCEPROP 2 LAST CDS_LIB mstr_standard
J 0
(-1800 1800);
PAINT ORANGE (-1800 1800);
DISPLAY INVISIBLE (-1800 1800);
FORCEPROP 2 LAST PATH I266
J 0
(-1625 1875);
DISPLAY 1.021277 (-1625 1875);
PAINT ORANGE (-1625 1875);
DISPLAY INVISIBLE (-1625 1875);
FORCEPROP 1 LAST OFFPAGE TRUE
J 0
(-1475 1675);
DISPLAY 0.872340 (-1475 1675);
PAINT GREEN (-1475 1675);
DISPLAY INVISIBLE (-1475 1675);
FORCEPROP 1 LAST COMMENT_BODY TRUE
J 0
(-1825 1700);
DISPLAY 0.872340 (-1825 1700);
PAINT GREEN (-1825 1700);
DISPLAY INVISIBLE (-1825 1700);
FORCEADD OFFPAGE..4
(-1800 1750);
FORCEPROP 2 LAST $XR0 156 
J 0
(-1614 1750);
DISPLAY 0.638298 (-1614 1750);
PAINT MONO (-1614 1750);
FORCEPROP 2 LAST CDS_LIB mstr_standard
J 0
(-1800 1750);
PAINT ORANGE (-1800 1750);
DISPLAY INVISIBLE (-1800 1750);
FORCEPROP 2 LAST PATH I267
J 0
(-1625 1825);
DISPLAY 1.021277 (-1625 1825);
PAINT ORANGE (-1625 1825);
DISPLAY INVISIBLE (-1625 1825);
FORCEPROP 1 LAST OFFPAGE TRUE
J 0
(-1475 1625);
DISPLAY 0.872340 (-1475 1625);
PAINT GREEN (-1475 1625);
DISPLAY INVISIBLE (-1475 1625);
FORCEPROP 1 LAST COMMENT_BODY TRUE
J 0
(-1825 1650);
DISPLAY 0.872340 (-1825 1650);
PAINT GREEN (-1825 1650);
DISPLAY INVISIBLE (-1825 1650);
FORCEADD OFFPAGE..4
(-1800 1700);
FORCEPROP 2 LAST $XR0 156 
J 0
(-1614 1700);
DISPLAY 0.638298 (-1614 1700);
PAINT MONO (-1614 1700);
FORCEPROP 2 LAST CDS_LIB mstr_standard
J 0
(-1800 1700);
PAINT ORANGE (-1800 1700);
DISPLAY INVISIBLE (-1800 1700);
FORCEPROP 2 LAST PATH I268
J 0
(-1625 1775);
DISPLAY 1.021277 (-1625 1775);
PAINT ORANGE (-1625 1775);
DISPLAY INVISIBLE (-1625 1775);
FORCEPROP 1 LAST OFFPAGE TRUE
J 0
(-1475 1575);
DISPLAY 0.872340 (-1475 1575);
PAINT GREEN (-1475 1575);
DISPLAY INVISIBLE (-1475 1575);
FORCEPROP 1 LAST COMMENT_BODY TRUE
J 0
(-1825 1600);
DISPLAY 0.872340 (-1825 1600);
PAINT GREEN (-1825 1600);
DISPLAY INVISIBLE (-1825 1600);
FORCEADD OFFPAGE..1
(-6350 4450);
FORCEPROP 2 LAST $XR0 103 
J 0
(-6602 4450);
DISPLAY 0.638298 (-6602 4450);
PAINT MONO (-6602 4450);
FORCEPROP 2 LAST CDS_LIB mstr_standard
J 0
(-6350 4450);
PAINT MONO (-6350 4450);
DISPLAY INVISIBLE (-6350 4450);
FORCEPROP 2 LAST PATH I4
J 0
(-6300 4525);
DISPLAY 1.361702 (-6300 4525);
PAINT ORANGE (-6300 4525);
DISPLAY INVISIBLE (-6300 4525);
FORCEPROP 1 LAST OFFPAGE TRUE
J 0
(-6025 4325);
DISPLAY 1.170213 (-6025 4325);
PAINT GREEN (-6025 4325);
DISPLAY INVISIBLE (-6025 4325);
FORCEPROP 1 LAST COMMENT_BODY TRUE
J 0
(-6225 4350);
DISPLAY 1.170213 (-6225 4350);
PAINT PEACH (-6225 4350);
DISPLAY INVISIBLE (-6225 4350);
FORCEADD OFFPAGE..6
(-6375 1500);
FORCEPROP 2 LAST $XR0 55 
J 0
(-6624 1500);
DISPLAY 0.638298 (-6624 1500);
PAINT MONO (-6624 1500);
FORCEPROP 2 LAST $XR1 112 
J 0
(-6744 1500);
DISPLAY 0.638298 (-6744 1500);
PAINT MONO (-6744 1500);
FORCEPROP 2 LAST CDS_LIB mstr_standard
J 0
(-6375 1500);
PAINT MONO (-6375 1500);
DISPLAY INVISIBLE (-6375 1500);
FORCEPROP 2 LAST PATH I43
J 0
(-6325 1575);
DISPLAY 1.361702 (-6325 1575);
PAINT ORANGE (-6325 1575);
DISPLAY INVISIBLE (-6325 1575);
FORCEPROP 1 LAST OFFPAGE TRUE
J 0
(-6050 1375);
DISPLAY 1.170213 (-6050 1375);
PAINT GREEN (-6050 1375);
DISPLAY INVISIBLE (-6050 1375);
FORCEPROP 1 LAST COMMENT_BODY TRUE
J 0
(-6275 1425);
DISPLAY 1.170213 (-6275 1425);
PAINT PEACH (-6275 1425);
DISPLAY INVISIBLE (-6275 1425);
FORCEADD OFFPAGE..6
(-6375 1450);
FORCEPROP 2 LAST $XR0 55 
J 0
(-6829 1450);
DISPLAY 0.638298 (-6829 1450);
PAINT MONO (-6829 1450);
DISPLAY INVISIBLE (-6829 1450);
FORCEPROP 2 LAST $XR1 112 
J 0
(-6829 1450);
DISPLAY 0.638298 (-6829 1450);
PAINT MONO (-6829 1450);
DISPLAY INVISIBLE (-6829 1450);
FORCEPROP 2 LAST CDS_LIB mstr_standard
J 0
(-6375 1450);
PAINT MONO (-6375 1450);
DISPLAY INVISIBLE (-6375 1450);
FORCEPROP 2 LAST PATH I44
J 0
(-6325 1525);
DISPLAY 1.361702 (-6325 1525);
PAINT ORANGE (-6325 1525);
DISPLAY INVISIBLE (-6325 1525);
FORCEPROP 1 LAST OFFPAGE TRUE
J 0
(-6050 1325);
DISPLAY 1.170213 (-6050 1325);
PAINT GREEN (-6050 1325);
DISPLAY INVISIBLE (-6050 1325);
FORCEPROP 1 LAST COMMENT_BODY TRUE
J 0
(-6275 1375);
DISPLAY 1.170213 (-6275 1375);
PAINT PEACH (-6275 1375);
DISPLAY INVISIBLE (-6275 1375);
FORCEADD OFFPAGE..1
(-6375 1350);
FORCEPROP 2 LAST $XR0 112 
J 0
(-6627 1350);
DISPLAY 0.638298 (-6627 1350);
PAINT MONO (-6627 1350);
FORCEPROP 2 LAST CDS_LIB mstr_standard
J 0
(-6375 1350);
PAINT MONO (-6375 1350);
DISPLAY INVISIBLE (-6375 1350);
FORCEPROP 2 LAST PATH I47
J 0
(-6325 1425);
DISPLAY 1.361702 (-6325 1425);
PAINT ORANGE (-6325 1425);
DISPLAY INVISIBLE (-6325 1425);
FORCEPROP 1 LAST OFFPAGE TRUE
J 0
(-6050 1225);
DISPLAY 1.170213 (-6050 1225);
PAINT GREEN (-6050 1225);
DISPLAY INVISIBLE (-6050 1225);
FORCEPROP 1 LAST COMMENT_BODY TRUE
J 0
(-6250 1250);
DISPLAY 1.170213 (-6250 1250);
PAINT PEACH (-6250 1250);
DISPLAY INVISIBLE (-6250 1250);
FORCEADD OFFPAGE..1
(-6375 1300);
FORCEPROP 2 LAST $XR0 111 
J 0
(-6627 1300);
DISPLAY 0.638298 (-6627 1300);
PAINT MONO (-6627 1300);
FORCEPROP 2 LAST $XR1 55 
J 0
(-6717 1300);
DISPLAY 0.638298 (-6717 1300);
PAINT MONO (-6717 1300);
FORCEPROP 2 LAST $XR2 112 
J 0
(-6837 1300);
DISPLAY 0.638298 (-6837 1300);
PAINT MONO (-6837 1300);
FORCEPROP 2 LAST CDS_LIB mstr_standard
J 0
(-6375 1300);
PAINT MONO (-6375 1300);
DISPLAY INVISIBLE (-6375 1300);
FORCEPROP 2 LAST PATH I48
J 0
(-6325 1375);
DISPLAY 1.361702 (-6325 1375);
PAINT ORANGE (-6325 1375);
DISPLAY INVISIBLE (-6325 1375);
FORCEPROP 1 LAST OFFPAGE TRUE
J 0
(-6050 1175);
DISPLAY 1.170213 (-6050 1175);
PAINT GREEN (-6050 1175);
DISPLAY INVISIBLE (-6050 1175);
FORCEPROP 1 LAST COMMENT_BODY TRUE
J 0
(-6250 1200);
DISPLAY 1.170213 (-6250 1200);
PAINT PEACH (-6250 1200);
DISPLAY INVISIBLE (-6250 1200);
FORCEADD OFFPAGE..1
(-6375 1250);
FORCEPROP 2 LAST $XR0 112 
J 0
(-6627 1250);
DISPLAY 0.638298 (-6627 1250);
PAINT MONO (-6627 1250);
FORCEPROP 2 LAST $XR1 55 
J 0
(-6717 1250);
DISPLAY 0.638298 (-6717 1250);
PAINT MONO (-6717 1250);
FORCEPROP 2 LAST CDS_LIB mstr_standard
J 0
(-6375 1250);
PAINT MONO (-6375 1250);
DISPLAY INVISIBLE (-6375 1250);
FORCEPROP 2 LAST PATH I49
J 0
(-6325 1325);
DISPLAY 1.361702 (-6325 1325);
PAINT ORANGE (-6325 1325);
DISPLAY INVISIBLE (-6325 1325);
FORCEPROP 1 LAST OFFPAGE TRUE
J 0
(-6050 1125);
DISPLAY 1.170213 (-6050 1125);
PAINT GREEN (-6050 1125);
DISPLAY INVISIBLE (-6050 1125);
FORCEPROP 1 LAST COMMENT_BODY TRUE
J 0
(-6250 1150);
DISPLAY 1.170213 (-6250 1150);
PAINT PEACH (-6250 1150);
DISPLAY INVISIBLE (-6250 1150);
FORCEADD OFFPAGE..1
(-6350 4350);
FORCEPROP 2 LAST $XR0 103 
J 0
(-6602 4350);
DISPLAY 0.638298 (-6602 4350);
PAINT MONO (-6602 4350);
FORCEPROP 2 LAST CDS_LIB mstr_standard
J 0
(-6350 4350);
PAINT MONO (-6350 4350);
DISPLAY INVISIBLE (-6350 4350);
FORCEPROP 2 LAST PATH I5
J 0
(-6300 4425);
DISPLAY 1.361702 (-6300 4425);
PAINT ORANGE (-6300 4425);
DISPLAY INVISIBLE (-6300 4425);
FORCEPROP 1 LAST OFFPAGE TRUE
J 0
(-6025 4225);
DISPLAY 1.170213 (-6025 4225);
PAINT GREEN (-6025 4225);
DISPLAY INVISIBLE (-6025 4225);
FORCEPROP 1 LAST COMMENT_BODY TRUE
J 0
(-6225 4250);
DISPLAY 1.170213 (-6225 4250);
PAINT PEACH (-6225 4250);
DISPLAY INVISIBLE (-6225 4250);
FORCEADD OFFPAGE..1
(-6375 1200);
FORCEPROP 2 LAST $XR0 112 
J 0
(-6627 1200);
DISPLAY 0.638298 (-6627 1200);
PAINT MONO (-6627 1200);
FORCEPROP 2 LAST $XR1 55 
J 0
(-6717 1200);
DISPLAY 0.638298 (-6717 1200);
PAINT MONO (-6717 1200);
FORCEPROP 2 LAST CDS_LIB mstr_standard
J 0
(-6375 1200);
PAINT MONO (-6375 1200);
DISPLAY INVISIBLE (-6375 1200);
FORCEPROP 2 LAST PATH I50
J 0
(-6325 1275);
DISPLAY 1.361702 (-6325 1275);
PAINT ORANGE (-6325 1275);
DISPLAY INVISIBLE (-6325 1275);
FORCEPROP 1 LAST OFFPAGE TRUE
J 0
(-6050 1075);
DISPLAY 1.170213 (-6050 1075);
PAINT GREEN (-6050 1075);
DISPLAY INVISIBLE (-6050 1075);
FORCEPROP 1 LAST COMMENT_BODY TRUE
J 0
(-6250 1100);
DISPLAY 1.170213 (-6250 1100);
PAINT PEACH (-6250 1100);
DISPLAY INVISIBLE (-6250 1100);
FORCEADD OFFPAGE..1
(-6350 4300);
FORCEPROP 2 LAST $XR0 103 
J 0
(-6602 4300);
DISPLAY 0.638298 (-6602 4300);
PAINT MONO (-6602 4300);
FORCEPROP 2 LAST CDS_LIB mstr_standard
J 0
(-6350 4300);
PAINT MONO (-6350 4300);
DISPLAY INVISIBLE (-6350 4300);
FORCEPROP 2 LAST PATH I6
J 0
(-6300 4375);
DISPLAY 1.361702 (-6300 4375);
PAINT ORANGE (-6300 4375);
DISPLAY INVISIBLE (-6300 4375);
FORCEPROP 1 LAST OFFPAGE TRUE
J 0
(-6025 4175);
DISPLAY 1.170213 (-6025 4175);
PAINT GREEN (-6025 4175);
DISPLAY INVISIBLE (-6025 4175);
FORCEPROP 1 LAST COMMENT_BODY TRUE
J 0
(-6225 4200);
DISPLAY 1.170213 (-6225 4200);
PAINT PEACH (-6225 4200);
DISPLAY INVISIBLE (-6225 4200);
FORCEADD OFFPAGE..3
(-1825 3650);
FORCEPROP 2 LAST $XR0 92 
J 0
(-1611 3650);
DISPLAY 0.638298 (-1611 3650);
PAINT MONO (-1611 3650);
FORCEPROP 2 LAST CDS_LIB mstr_standard
J 0
(-1825 3650);
PAINT MONO (-1825 3650);
DISPLAY INVISIBLE (-1825 3650);
FORCEPROP 2 LAST PATH I66
J 0
(-1650 3725);
DISPLAY 1.361702 (-1650 3725);
PAINT ORANGE (-1650 3725);
DISPLAY INVISIBLE (-1650 3725);
FORCEPROP 1 LAST OFFPAGE TRUE
J 0
(-1500 3525);
DISPLAY 0.872340 (-1500 3525);
PAINT GREEN (-1500 3525);
DISPLAY INVISIBLE (-1500 3525);
FORCEPROP 1 LAST COMMENT_BODY TRUE
J 0
(-1875 3550);
DISPLAY 0.872340 (-1875 3550);
PAINT GREEN (-1875 3550);
DISPLAY INVISIBLE (-1875 3550);
FORCEADD OFFPAGE..2
(-1800 3550);
FORCEPROP 2 LAST $XR0 92 
J 0
(-1611 3550);
DISPLAY 0.638298 (-1611 3550);
PAINT MONO (-1611 3550);
FORCEPROP 2 LAST CDS_LIB mstr_standard
J 0
(-1800 3550);
PAINT MONO (-1800 3550);
DISPLAY INVISIBLE (-1800 3550);
FORCEPROP 2 LAST PATH I67
J 0
(-1625 3625);
DISPLAY 1.361702 (-1625 3625);
PAINT ORANGE (-1625 3625);
DISPLAY INVISIBLE (-1625 3625);
FORCEPROP 1 LAST OFFPAGE TRUE
J 0
(-1475 3425);
DISPLAY 0.872340 (-1475 3425);
PAINT GREEN (-1475 3425);
DISPLAY INVISIBLE (-1475 3425);
FORCEPROP 1 LAST COMMENT_BODY TRUE
J 0
(-1845 3455);
DISPLAY 0.872340 (-1845 3455);
PAINT GREEN (-1845 3455);
DISPLAY INVISIBLE (-1845 3455);
FORCEADD OFFPAGE..2
(-1800 3500);
FORCEPROP 2 LAST $XR0 93 
J 0
(-1611 3500);
DISPLAY 0.638298 (-1611 3500);
PAINT MONO (-1611 3500);
FORCEPROP 2 LAST CDS_LIB mstr_standard
J 0
(-1800 3500);
PAINT MONO (-1800 3500);
DISPLAY INVISIBLE (-1800 3500);
FORCEPROP 2 LAST PATH I68
J 0
(-1625 3575);
DISPLAY 1.361702 (-1625 3575);
PAINT ORANGE (-1625 3575);
DISPLAY INVISIBLE (-1625 3575);
FORCEPROP 1 LAST OFFPAGE TRUE
J 0
(-1475 3375);
DISPLAY 0.872340 (-1475 3375);
PAINT GREEN (-1475 3375);
DISPLAY INVISIBLE (-1475 3375);
FORCEPROP 1 LAST COMMENT_BODY TRUE
J 0
(-1845 3405);
DISPLAY 0.872340 (-1845 3405);
PAINT GREEN (-1845 3405);
DISPLAY INVISIBLE (-1845 3405);
FORCEADD OFFPAGE..2
(-1800 3450);
FORCEPROP 2 LAST $XR0 93 
J 0
(-1611 3450);
DISPLAY 0.638298 (-1611 3450);
PAINT MONO (-1611 3450);
FORCEPROP 2 LAST CDS_LIB mstr_standard
J 0
(-1800 3450);
PAINT MONO (-1800 3450);
DISPLAY INVISIBLE (-1800 3450);
FORCEPROP 2 LAST PATH I69
J 0
(-1625 3525);
DISPLAY 1.361702 (-1625 3525);
PAINT ORANGE (-1625 3525);
DISPLAY INVISIBLE (-1625 3525);
FORCEPROP 1 LAST OFFPAGE TRUE
J 0
(-1475 3325);
DISPLAY 0.872340 (-1475 3325);
PAINT GREEN (-1475 3325);
DISPLAY INVISIBLE (-1475 3325);
FORCEPROP 1 LAST COMMENT_BODY TRUE
J 0
(-1845 3355);
DISPLAY 0.872340 (-1845 3355);
PAINT GREEN (-1845 3355);
DISPLAY INVISIBLE (-1845 3355);
FORCEADD OFFPAGE..1
(-6350 4050);
FORCEPROP 2 LAST $XR0 96 
J 0
(-6601 4050);
DISPLAY 0.638298 (-6601 4050);
PAINT MONO (-6601 4050);
FORCEPROP 2 LAST CDS_LIB mstr_standard
J 0
(-6350 4050);
PAINT MONO (-6350 4050);
DISPLAY INVISIBLE (-6350 4050);
FORCEPROP 2 LAST PATH I7
J 0
(-6300 4125);
DISPLAY 1.361702 (-6300 4125);
PAINT ORANGE (-6300 4125);
DISPLAY INVISIBLE (-6300 4125);
FORCEPROP 1 LAST OFFPAGE TRUE
J 0
(-6025 3925);
DISPLAY 1.170213 (-6025 3925);
PAINT GREEN (-6025 3925);
DISPLAY INVISIBLE (-6025 3925);
FORCEPROP 1 LAST COMMENT_BODY TRUE
J 0
(-6225 3950);
DISPLAY 1.170213 (-6225 3950);
PAINT PEACH (-6225 3950);
DISPLAY INVISIBLE (-6225 3950);
FORCEADD OFFPAGE..3
(-1825 3200);
FORCEPROP 2 LAST $XR0 95 
J 0
(-1611 3200);
DISPLAY 0.638298 (-1611 3200);
PAINT MONO (-1611 3200);
FORCEPROP 2 LAST $XR1 93 
J 0
(-1521 3200);
DISPLAY 0.638298 (-1521 3200);
PAINT MONO (-1521 3200);
FORCEPROP 2 LAST CDS_LIB mstr_standard
J 0
(-1825 3200);
PAINT MONO (-1825 3200);
DISPLAY INVISIBLE (-1825 3200);
FORCEPROP 2 LAST PATH I71
J 0
(-1650 3275);
DISPLAY 1.361702 (-1650 3275);
PAINT ORANGE (-1650 3275);
DISPLAY INVISIBLE (-1650 3275);
FORCEPROP 1 LAST OFFPAGE TRUE
J 0
(-1500 3075);
DISPLAY 1.170213 (-1500 3075);
PAINT GREEN (-1500 3075);
DISPLAY INVISIBLE (-1500 3075);
FORCEPROP 1 LAST COMMENT_BODY TRUE
J 0
(-1875 3100);
DISPLAY 1.170213 (-1875 3100);
PAINT PEACH (-1875 3100);
DISPLAY INVISIBLE (-1875 3100);
FORCEADD OFFPAGE..2
(-1800 3150);
FORCEPROP 2 LAST $XR0 92 
J 0
(-1611 3150);
DISPLAY 0.638298 (-1611 3150);
PAINT MONO (-1611 3150);
FORCEPROP 2 LAST CDS_LIB mstr_standard
J 0
(-1800 3150);
PAINT MONO (-1800 3150);
DISPLAY INVISIBLE (-1800 3150);
FORCEPROP 2 LAST PATH I72
J 0
(-1625 3225);
DISPLAY 1.361702 (-1625 3225);
PAINT ORANGE (-1625 3225);
DISPLAY INVISIBLE (-1625 3225);
FORCEPROP 1 LAST OFFPAGE TRUE
J 0
(-1475 3025);
DISPLAY 1.170213 (-1475 3025);
PAINT GREEN (-1475 3025);
DISPLAY INVISIBLE (-1475 3025);
FORCEPROP 1 LAST COMMENT_BODY TRUE
J 0
(-1845 3055);
DISPLAY 1.170213 (-1845 3055);
PAINT PEACH (-1845 3055);
DISPLAY INVISIBLE (-1845 3055);
FORCEADD OFFPAGE..4
(-2100 3050);
FORCEPROP 2 LAST $XR0 90 
J 0
(-1914 3050);
DISPLAY 0.638298 (-1914 3050);
PAINT MONO (-1914 3050);
FORCEPROP 2 LAST CDS_LIB mstr_standard
J 0
(-2100 3050);
PAINT MONO (-2100 3050);
DISPLAY INVISIBLE (-2100 3050);
FORCEPROP 2 LAST PATH I74
J 0
(-1925 3125);
DISPLAY 1.361702 (-1925 3125);
PAINT ORANGE (-1925 3125);
DISPLAY INVISIBLE (-1925 3125);
FORCEPROP 1 LAST OFFPAGE TRUE
J 0
(-1775 2925);
DISPLAY 1.170213 (-1775 2925);
PAINT GREEN (-1775 2925);
DISPLAY INVISIBLE (-1775 2925);
FORCEPROP 1 LAST COMMENT_BODY TRUE
J 0
(-2125 2950);
DISPLAY 1.170213 (-2125 2950);
PAINT PEACH (-2125 2950);
DISPLAY INVISIBLE (-2125 2950);
FORCEADD OFFPAGE..4
(-2100 3000);
FORCEPROP 2 LAST $XR0 90 
J 0
(-1914 3000);
DISPLAY 0.638298 (-1914 3000);
PAINT MONO (-1914 3000);
FORCEPROP 2 LAST CDS_LIB mstr_standard
J 0
(-2100 3000);
PAINT MONO (-2100 3000);
DISPLAY INVISIBLE (-2100 3000);
FORCEPROP 2 LAST PATH I75
J 0
(-1925 3075);
DISPLAY 1.361702 (-1925 3075);
PAINT ORANGE (-1925 3075);
DISPLAY INVISIBLE (-1925 3075);
FORCEPROP 1 LAST OFFPAGE TRUE
J 0
(-1775 2875);
DISPLAY 1.170213 (-1775 2875);
PAINT GREEN (-1775 2875);
DISPLAY INVISIBLE (-1775 2875);
FORCEPROP 1 LAST COMMENT_BODY TRUE
J 0
(-2125 2900);
DISPLAY 1.170213 (-2125 2900);
PAINT PEACH (-2125 2900);
DISPLAY INVISIBLE (-2125 2900);
FORCEADD OFFPAGE..4
(-2100 2950);
FORCEPROP 2 LAST $XR0 90 
J 0
(-1914 2950);
DISPLAY 0.638298 (-1914 2950);
PAINT MONO (-1914 2950);
FORCEPROP 2 LAST $XR1 156 
J 0
(-1824 2950);
DISPLAY 0.638298 (-1824 2950);
PAINT MONO (-1824 2950);
FORCEPROP 2 LAST CDS_LIB mstr_standard
J 0
(-2100 2950);
PAINT MONO (-2100 2950);
DISPLAY INVISIBLE (-2100 2950);
FORCEPROP 2 LAST PATH I76
J 0
(-1925 3025);
DISPLAY 1.361702 (-1925 3025);
PAINT ORANGE (-1925 3025);
DISPLAY INVISIBLE (-1925 3025);
FORCEPROP 1 LAST OFFPAGE TRUE
J 0
(-1775 2825);
DISPLAY 1.170213 (-1775 2825);
PAINT GREEN (-1775 2825);
DISPLAY INVISIBLE (-1775 2825);
FORCEPROP 1 LAST COMMENT_BODY TRUE
J 0
(-2125 2850);
DISPLAY 1.170213 (-2125 2850);
PAINT PEACH (-2125 2850);
DISPLAY INVISIBLE (-2125 2850);
FORCEADD OFFPAGE..4
(-2100 2900);
FORCEPROP 2 LAST $XR0 90 
J 0
(-1914 2900);
DISPLAY 0.638298 (-1914 2900);
PAINT MONO (-1914 2900);
FORCEPROP 2 LAST CDS_LIB mstr_standard
J 0
(-2100 2900);
PAINT MONO (-2100 2900);
DISPLAY INVISIBLE (-2100 2900);
FORCEPROP 2 LAST PATH I77
J 0
(-1925 2975);
DISPLAY 1.361702 (-1925 2975);
PAINT ORANGE (-1925 2975);
DISPLAY INVISIBLE (-1925 2975);
FORCEPROP 1 LAST OFFPAGE TRUE
J 0
(-1775 2775);
DISPLAY 1.170213 (-1775 2775);
PAINT GREEN (-1775 2775);
DISPLAY INVISIBLE (-1775 2775);
FORCEPROP 1 LAST COMMENT_BODY TRUE
J 0
(-2125 2800);
DISPLAY 1.170213 (-2125 2800);
PAINT PEACH (-2125 2800);
DISPLAY INVISIBLE (-2125 2800);
FORCEADD OFFPAGE..4
(-2100 2850);
FORCEPROP 2 LAST $XR0 90 
J 0
(-1914 2850);
DISPLAY 0.638298 (-1914 2850);
PAINT MONO (-1914 2850);
FORCEPROP 2 LAST CDS_LIB mstr_standard
J 0
(-2100 2850);
PAINT MONO (-2100 2850);
DISPLAY INVISIBLE (-2100 2850);
FORCEPROP 2 LAST PATH I78
J 0
(-1925 2925);
DISPLAY 1.361702 (-1925 2925);
PAINT ORANGE (-1925 2925);
DISPLAY INVISIBLE (-1925 2925);
FORCEPROP 1 LAST OFFPAGE TRUE
J 0
(-1775 2725);
DISPLAY 1.170213 (-1775 2725);
PAINT GREEN (-1775 2725);
DISPLAY INVISIBLE (-1775 2725);
FORCEPROP 1 LAST COMMENT_BODY TRUE
J 0
(-2125 2750);
DISPLAY 1.170213 (-2125 2750);
PAINT PEACH (-2125 2750);
DISPLAY INVISIBLE (-2125 2750);
FORCEADD OFFPAGE..4
(-2100 2800);
FORCEPROP 2 LAST $XR0 90 
J 0
(-1914 2800);
DISPLAY 0.638298 (-1914 2800);
PAINT MONO (-1914 2800);
FORCEPROP 2 LAST CDS_LIB mstr_standard
J 0
(-2100 2800);
PAINT MONO (-2100 2800);
DISPLAY INVISIBLE (-2100 2800);
FORCEPROP 2 LAST PATH I79
J 0
(-1925 2875);
DISPLAY 1.361702 (-1925 2875);
PAINT ORANGE (-1925 2875);
DISPLAY INVISIBLE (-1925 2875);
FORCEPROP 1 LAST OFFPAGE TRUE
J 0
(-1775 2675);
DISPLAY 1.170213 (-1775 2675);
PAINT GREEN (-1775 2675);
DISPLAY INVISIBLE (-1775 2675);
FORCEPROP 1 LAST COMMENT_BODY TRUE
J 0
(-2125 2700);
DISPLAY 1.170213 (-2125 2700);
PAINT PEACH (-2125 2700);
DISPLAY INVISIBLE (-2125 2700);
FORCEADD OFFPAGE..1
(-6350 4000);
FORCEPROP 2 LAST $XR0 96 
J 0
(-6601 4000);
DISPLAY 0.638298 (-6601 4000);
PAINT MONO (-6601 4000);
FORCEPROP 2 LAST CDS_LIB mstr_standard
J 0
(-6350 4000);
PAINT MONO (-6350 4000);
DISPLAY INVISIBLE (-6350 4000);
FORCEPROP 2 LAST PATH I8
J 0
(-6300 4075);
DISPLAY 1.361702 (-6300 4075);
PAINT ORANGE (-6300 4075);
DISPLAY INVISIBLE (-6300 4075);
FORCEPROP 1 LAST OFFPAGE TRUE
J 0
(-6025 3875);
DISPLAY 1.170213 (-6025 3875);
PAINT GREEN (-6025 3875);
DISPLAY INVISIBLE (-6025 3875);
FORCEPROP 1 LAST COMMENT_BODY TRUE
J 0
(-6225 3900);
DISPLAY 1.170213 (-6225 3900);
PAINT PEACH (-6225 3900);
DISPLAY INVISIBLE (-6225 3900);
FORCEADD OFFPAGE..3
(-2125 2750);
FORCEPROP 2 LAST $XR0 97 
J 0
(-1911 2750);
DISPLAY 0.638298 (-1911 2750);
PAINT MONO (-1911 2750);
FORCEPROP 2 LAST $XR1 157 
J 0
(-1821 2750);
DISPLAY 0.638298 (-1821 2750);
PAINT MONO (-1821 2750);
FORCEPROP 2 LAST CDS_LIB mstr_standard
J 0
(-2125 2750);
PAINT MONO (-2125 2750);
DISPLAY INVISIBLE (-2125 2750);
FORCEPROP 2 LAST PATH I80
J 0
(-1950 2825);
DISPLAY 1.361702 (-1950 2825);
PAINT ORANGE (-1950 2825);
DISPLAY INVISIBLE (-1950 2825);
FORCEPROP 1 LAST OFFPAGE TRUE
J 0
(-1800 2625);
DISPLAY 1.170213 (-1800 2625);
PAINT GREEN (-1800 2625);
DISPLAY INVISIBLE (-1800 2625);
FORCEPROP 1 LAST COMMENT_BODY TRUE
J 0
(-2175 2650);
DISPLAY 1.170213 (-2175 2650);
PAINT PEACH (-2175 2650);
DISPLAY INVISIBLE (-2175 2650);
FORCEADD OFFPAGE..5
(-6350 3900);
FORCEPROP 2 LAST $XR0 43 
J 0
(-6574 3900);
DISPLAY 0.638298 (-6574 3900);
PAINT MONO (-6574 3900);
FORCEPROP 2 LAST $XR1 44 
J 0
(-6664 3900);
DISPLAY 0.638298 (-6664 3900);
PAINT MONO (-6664 3900);
FORCEPROP 2 LAST $XR2 45 
J 0
(-6754 3900);
DISPLAY 0.638298 (-6754 3900);
PAINT MONO (-6754 3900);
FORCEPROP 2 LAST $XR3 46 
J 0
(-6844 3900);
DISPLAY 0.638298 (-6844 3900);
PAINT MONO (-6844 3900);
FORCEPROP 2 LAST $XR4 47 
J 0
(-6934 3900);
DISPLAY 0.638298 (-6934 3900);
PAINT MONO (-6934 3900);
FORCEPROP 2 LAST $XR5 48 
J 0
(-7024 3900);
DISPLAY 0.638298 (-7024 3900);
PAINT MONO (-7024 3900);
FORCEPROP 2 LAST CDS_LIB mstr_standard
J 0
(-6350 3900);
PAINT MONO (-6350 3900);
DISPLAY INVISIBLE (-6350 3900);
FORCEPROP 2 LAST PATH I9
J 0
(-6300 3975);
DISPLAY 1.361702 (-6300 3975);
PAINT ORANGE (-6300 3975);
DISPLAY INVISIBLE (-6300 3975);
FORCEPROP 1 LAST OFFPAGE TRUE
J 0
(-6025 3775);
DISPLAY 1.170213 (-6025 3775);
PAINT GREEN (-6025 3775);
DISPLAY INVISIBLE (-6025 3775);
FORCEPROP 1 LAST COMMENT_BODY TRUE
J 0
(-6250 3825);
DISPLAY 1.170213 (-6250 3825);
PAINT PEACH (-6250 3825);
DISPLAY INVISIBLE (-6250 3825);
FORCEADD DESIGN_NOTE..1
(-4675 850);
FORCEPROP 0 LAST L1 CPU SYMBOLS 1-30 ARE PRELIMINARY AND SUBJECT TO CHANGE
J 0
(-4875 725);
DISPLAY 1.021277 (-4875 725);
PAINT ORANGE (-4875 725);
FORCEPROP 2 LAST CDS_LIB mstr_symbols
J 0
(-4675 850);
PAINT ORANGE (-4675 850);
DISPLAY INVISIBLE (-4675 850);
FORCEPROP 1 LAST COMMENT_BODY TRUE
J 0
(-4650 950);
DISPLAY 0.978723 (-4650 950);
PAINT ORANGE (-4650 950);
DISPLAY INVISIBLE (-4650 950);
FORCEADD CAD_NOTE..1
(-7600 2625);
FORCEPROP 0 LAST LINE PLACE RCOMP RESISTORS
J 0
(-7750 2500);
PAINT WHITE (-7750 2500);
FORCEPROP 0 LAST LINE2 WITHIN 1 IN OF CPU PINS
J 0
(-7750 2425);
PAINT WHITE (-7750 2425);
FORCEPROP 2 LAST CDS_LIB mstr_symbols
J 0
(-7600 2625);
PAINT ORANGE (-7600 2625);
DISPLAY INVISIBLE (-7600 2625);
FORCEPROP 1 LAST COMMENT_BODY TRUE
J 0
(-7575 2725);
DISPLAY 1.340426 (-7575 2725);
PAINT GREEN (-7575 2725);
DISPLAY INVISIBLE (-7575 2725);
FORCEADD BOM_NOTE..1
(-7725 4850);
FORCEPROP 0 LAST L1 ASSEMBLY IPN PRIMARY :H63715-002,
J 0
(-7875 4725);
DISPLAY 0.851064 (-7875 4725);
PAINT WHITE (-7875 4725);
FORCEPROP 2 LAST BOM_COST SB
J 0
(-7875 4825);
DISPLAY 1.361702 (-7875 4825);
PAINT ORANGE (-7875 4825);
DISPLAY INVISIBLE (-7875 4825);
FORCEPROP 2 LAST CDS_LIB mstr_symbols
J 0
(-7725 4850);
PAINT ORANGE (-7725 4850);
DISPLAY INVISIBLE (-7725 4850);
FORCEPROP 2 LAST ROOM SB_HEADERS
J 0
(-7875 4825);
DISPLAY 1.361702 (-7875 4825);
PAINT ORANGE (-7875 4825);
DISPLAY INVISIBLE (-7875 4825);
FORCEPROP 1 LAST COMMENT_BODY TRUE
J 0
(-7700 4950);
DISPLAY 1.319149 (-7700 4950);
PAINT ORANGE (-7700 4950);
DISPLAY INVISIBLE (-7700 4950);
FORCEADD CAD_NOTE..1
(-7725 1625);
FORCEPROP 0 LAST LINE2 WITHIN 1.1 IN OF CPU PINS
J 0
(-7875 1425);
PAINT WHITE (-7875 1425);
FORCEPROP 0 LAST LINE PLACE RBIAS RESISTORS
J 0
(-7875 1500);
PAINT WHITE (-7875 1500);
FORCEPROP 2 LAST CDS_LIB mstr_symbols
J 0
(-7725 1625);
PAINT ORANGE (-7725 1625);
DISPLAY INVISIBLE (-7725 1625);
FORCEPROP 1 LAST COMMENT_BODY TRUE
J 0
(-7700 1725);
DISPLAY 1.340426 (-7700 1725);
PAINT GREEN (-7700 1725);
DISPLAY INVISIBLE (-7700 1725);
FORCEADD PRELIM..10
(-4065 2840);
PAINT GRAY (-4065 2840);
FORCEPROP 2 LAST CDS_LIB mstr_misc
J 0
(-4065 2840);
PAINT ORANGE (-4065 2840);
DISPLAY INVISIBLE (-4065 2840);
FORCEPROP 1 LAST COMMENT_BODY TRUE
J 0
(-4065 2840);
PAINT PEACH (-4065 2840);
DISPLAY INVISIBLE (-4065 2840);
FORCEADD DESIGN_NOTE..1
(-1075 2050);
FORCEPROP 0 LAST L1 CPU0 PIROM ADDRESS: 0XA0
J 0
(-1275 1925);
DISPLAY 0.808511 (-1275 1925);
PAINT ORANGE (-1275 1925);
FORCEPROP 2 LAST CDS_LIB mstr_symbols
J 0
(-1075 2050);
PAINT ORANGE (-1075 2050);
DISPLAY INVISIBLE (-1075 2050);
FORCEPROP 1 LAST COMMENT_BODY TRUE
J 0
(-1050 2150);
DISPLAY 0.978723 (-1050 2150);
PAINT ORANGE (-1050 2150);
DISPLAY INVISIBLE (-1050 2150);
FORCEADD INTEL_CORP_BPAGE..1
(-50 0);
FORCEPROP 1 LAST CDS_CON_LAST_MODIFIED Tue Dec 01 11:51:15 2015
J 0
(-1475 325);
DISPLAY 1.340426 (-1475 325);
PAINT GREEN (-1475 325);
DISPLAY INVISIBLE (-1475 325);
FORCEPROP 1 LAST CUSTOM_TXT_CDS <CURRENT_DESIGN_SHEET> OF <TOTAL_DESIGN_SHEETS>
J 0
(-550 25);
PAINT GREEN (-550 25);
FORCEPROP 1 LAST CUSTOM_TXT_CDS <CON_LAST_MODIFIED>
J 0
(-1975 350);
PAINT GREEN (-1975 350);
FORCEPROP 2 LAST CUSTOM_TXT_CDS <XR_PAGE_TITLE>
J 0
(-7940 5250);
DISPLAY 0.638298 (-7940 5250);
PAINT PINK (-7940 5250);
DISPLAY INVISIBLE (-7940 5250);
FORCEPROP 1 LAST SCH_ADDRESS3 Santa Clara, CA 95052-8119
J 0
(-4025 25);
DISPLAY 0.617021 (-4025 25);
PAINT YELLOW (-4025 25);
FORCEPROP 1 LAST SCH_ADDRESS2 P.O. BOX 58119
J 0
(-4025 75);
DISPLAY 0.617021 (-4025 75);
PAINT YELLOW (-4025 75);
FORCEPROP 1 LAST SCH_ADDRESS1 2200 Mission College Blvd.
J 0
(-4025 125);
DISPLAY 0.617021 (-4025 125);
PAINT YELLOW (-4025 125);
FORCEPROP 1 LAST SCH_TITLE SKYLAKE - SKT0 - 1 OF 21
J 0
(-8000 50);
DISPLAY 1.212766 (-8000 50);
PAINT YELLOW (-8000 50);
FORCEPROP 1 LAST SCH_NUMBER H4694802
J 0
(-1350 150);
DISPLAY 1.212766 (-1350 150);
PAINT YELLOW (-1350 150);
FORCEPROP 1 LAST SCH_DEPT BESD
J 1
(-4500 100);
DISPLAY 1.212766 (-4500 100);
PAINT YELLOW (-4500 100);
FORCEPROP 1 LAST SCH_REV 2.420
J 0
(-300 150);
DISPLAY 0.978723 (-300 150);
PAINT YELLOW (-300 150);
FORCEPROP 2 LAST PAGE_BORDER TRUE
J 0
(-7940 5250);
DISPLAY 0.851064 (-7940 5250);
PAINT PINK (-7940 5250);
DISPLAY INVISIBLE (-7940 5250);
FORCEPROP 2 LAST CDS_LIB mstr_symbols
J 0
(-50 0);
PAINT ORANGE (-50 0);
DISPLAY INVISIBLE (-50 0);
FORCEPROP 1 LAST COMMENT_BODY TRUE
J 0
(-38 12);
DISPLAY 0.638298 (-38 12);
PAINT PEACH (-38 12);
DISPLAY INVISIBLE (-38 12);
FORCEPROP 2 LAST CDS_XR_PAGE_TITLE CR-21 : @BASEBOARD_FAB2_LIB.BASEBOARD_FAB2(SCH_1):PAGE21
J 0
(-7940 5250);
DISPLAY 0.638298 (-7940 5250);
PAINT PINK (-7940 5250);
DISPLAY INVISIBLE (-7940 5250);
WIRE 16 -1 (-1200 4400)(-1200 4525);
WIRE 16 -1 (-1200 4525)(-975 4525);
WIRE 16 -1 (-975 4400)(-975 4525);
WIRE 16 -1 (-975 4525)(-975 4575);
WIRE 16 -1 (-6625 2700)(-6625 2775);
WIRE 16 -1 (-6625 2700)(-6875 2700);
WIRE 16 -1 (-6875 2825)(-6875 2700);
WIRE 16 -1 (-7125 2700)(-6875 2700);
WIRE 16 -1 (-7125 2825)(-7125 2700);
WIRE 16 -1 (-7350 2700)(-7125 2700);
WIRE 16 -1 (-7350 2825)(-7350 2700);
WIRE 16 -1 (-7575 2700)(-7350 2700);
WIRE 16 -1 (-7575 2900)(-7575 2700);
WIRE 16 -1 (-7800 2700)(-7575 2700);
WIRE 16 -1 (-7800 2900)(-7800 2700);
WIRE 16 -1 (-7800 2700)(-7800 2625);
WIRE 16 -1 (-6925 1900)(-6925 1850);
WIRE 16 -1 (-6925 1850)(-7150 1850);
WIRE 16 -1 (-7150 1950)(-7150 1850);
WIRE 16 -1 (-7150 1850)(-7375 1850);
WIRE 16 -1 (-7375 1850)(-7375 2000);
WIRE 16 -1 (-7575 1850)(-7375 1850);
WIRE 16 -1 (-7575 2000)(-7575 1850);
WIRE 16 -1 (-7800 1850)(-7575 1850);
WIRE 16 -1 (-7800 1850)(-7800 2000);
WIRE 16 -1 (-7800 1775)(-7800 1850);
WIRE 16 -1 (-1475 2800)(-1475 2925);
WIRE 16 -1 (-1475 2925)(-1275 2925);
WIRE 16 -1 (-1275 2800)(-1275 2925);
WIRE 16 -1 (-1075 2925)(-1275 2925);
WIRE 16 -1 (-1075 2800)(-1075 2925);
WIRE 16 -1 (-875 2925)(-1075 2925);
WIRE 16 -1 (-875 2925)(-675 2925);
WIRE 16 -1 (-875 2925)(-875 2800);
WIRE 16 -1 (-675 2800)(-675 2925);
WIRE 16 -1 (-675 3000)(-675 2925);
WIRE 16 -1 (-1075 1550)(-1075 1675);
WIRE 16 -1 (-1200 3375)(-1200 3225);
WIRE 16 -1 (-975 3225)(-1200 3225);
WIRE 16 -1 (-975 3400)(-975 3225);
WIRE 16 -1 (-650 3225)(-975 3225);
WIRE 16 -1 (-650 3325)(-650 3225);
WIRE 16 -1 (-1900 4350)(-3125 4350);
FORCEPROP 2 LAST SIG_NAME PU_CPU0_EAR_N
J 0
(-2875 4360);
DISPLAY 0.617021 (-2875 4360);
PAINT ORANGE (-2875 4360);
WIRE 16 -1 (-1875 4250)(-2350 4250);
FORCEPROP 2 LAST SIG_NAME H_PM_SYNC_GTL
J 0
(-2260 4260);
DISPLAY 0.617021 (-2260 4260);
PAINT ORANGE (-2260 4260);
WIRE 16 -1 (-1875 4200)(-2275 4200);
FORCEPROP 0 LAST SIG_NAME H_PMSYNC_CLK_24M
J 0
(-2270 4210);
DISPLAY 0.617021 (-2270 4210);
PAINT ORANGE (-2270 4210);
WIRE 16 -1 (-1875 4100)(-3125 4100);
FORCEPROP 2 LAST SIG_NAME PECI_CPU_G
J 0
(-2875 4110);
DISPLAY 0.617021 (-2875 4110);
PAINT ORANGE (-2875 4110);
WIRE 16 -1 (-1900 4450)(-3125 4450);
FORCEPROP 2 LAST SIG_NAME RST_CPU0_G_N
J 0
(-2900 4460);
DISPLAY 0.617021 (-2900 4460);
PAINT ORANGE (-2900 4460);
WIRE 16 -1 (-1900 4500)(-3125 4500);
FORCEPROP 2 LAST SIG_NAME PWRGD_CPU0_G
J 0
(-2900 4510);
DISPLAY 0.617021 (-2900 4510);
PAINT ORANGE (-2900 4510);
WIRE 16 -1 (-3125 4250)(-2550 4250);
FORCEPROP 2 LAST SIG_NAME H_PM_SYNC_GTL_R1
J 0
(-2975 4260);
DISPLAY 0.617021 (-2975 4260);
PAINT ORANGE (-2975 4260);
FORCEPROP 2 LASTPROP $XRERR UNIQUE?
J 0
(-3215 4260);
DISPLAY 0.638298 (-3215 4260);
PAINT MONO (-3215 4260);
DISPLAY INVISIBLE (-3215 4260);
WIRE 16 -1 (-2475 4200)(-3125 4200);
FORCEPROP 2 LAST SIG_NAME H_PMSYNC_CLK_24M_CPU0
J 0
(-2975 4210);
DISPLAY 0.617021 (-2975 4210);
PAINT ORANGE (-2975 4210);
FORCEPROP 2 LASTPROP $XRERR UNIQUE?
J 0
(-3215 4210);
DISPLAY 0.638298 (-3215 4210);
PAINT MONO (-3215 4210);
DISPLAY INVISIBLE (-3215 4210);
WIRE 16 -1 (-1200 4200)(-1200 4000);
WIRE 16 -1 (-825 4000)(-1200 4000);
WIRE 16 -1 (-1200 4000)(-1875 4000);
FORCEPROP 2 LAST SIG_NAME SVID_DIO1_CPU0_R
J 0
(-1575 4010);
DISPLAY 0.617021 (-1575 4010);
PAINT ORANGE (-1575 4010);
WIRE 16 -1 (-800 3900)(-975 3900);
WIRE 16 -1 (-975 4200)(-975 3900);
WIRE 16 -1 (-1875 3900)(-975 3900);
FORCEPROP 2 LAST SIG_NAME SVID_ALERT1_CPU0_R_N
J 0
(-1575 3910);
DISPLAY 0.617021 (-1575 3910);
PAINT ORANGE (-1575 3910);
WIRE 16 -1 (-975 3600)(-975 3750);
WIRE 16 -1 (-800 3750)(-975 3750);
WIRE 16 -1 (-1875 3750)(-975 3750);
FORCEPROP 2 LAST SIG_NAME SVID_ALERT0_CPU0_R_N
J 0
(-1575 3760);
DISPLAY 0.617021 (-1575 3760);
PAINT ORANGE (-1575 3760);
WIRE 16 -1 (-600 2450)(-1475 2450);
WIRE 16 -1 (-1475 2600)(-1475 2450);
WIRE 16 -1 (-1475 2450)(-3125 2450);
FORCEPROP 2 LAST SIG_NAME FM_CPU0_PROC_ID1
J 0
(-2925 2460);
DISPLAY 0.617021 (-2925 2460);
PAINT ORANGE (-2925 2460);
WIRE 16 -1 (-1875 3950)(-800 3950);
FORCEPROP 2 LAST SIG_NAME SVID_CLK1_CPU0_R
J 0
(-1575 3960);
DISPLAY 0.617021 (-1575 3960);
PAINT ORANGE (-1575 3960);
WIRE 16 -1 (-1875 3800)(-800 3800);
FORCEPROP 2 LAST SIG_NAME SVID_CLK0_CPU0_R
J 0
(-1575 3810);
DISPLAY 0.617021 (-1575 3810);
PAINT ORANGE (-1575 3810);
WIRE 16 -1 (-825 3850)(-1200 3850);
WIRE 16 -1 (-1200 3575)(-1200 3850);
WIRE 16 -1 (-1200 3850)(-1875 3850);
FORCEPROP 2 LAST SIG_NAME SVID_DIO0_CPU0_R
J 0
(-1575 3860);
DISPLAY 0.617021 (-1575 3860);
PAINT ORANGE (-1575 3860);
WIRE 16 -1 (-1500 1000)(-1500 575);
WIRE 16 -1 (-1050 1000)(-1050 575);
WIRE 16 -1 (-3125 3150)(-1850 3150);
FORCEPROP 2 LAST SIG_NAME H_CPU0_THERMTRIP_G_N
J 0
(-2875 3160);
DISPLAY 0.617021 (-2875 3160);
PAINT ORANGE (-2875 3160);
WIRE 16 -1 (-3125 3200)(-1875 3200);
FORCEPROP 2 LAST SIG_NAME H_CPU0_PROCHOT_G_N
J 0
(-2875 3210);
DISPLAY 0.617021 (-2875 3210);
PAINT ORANGE (-2875 3210);
WIRE 16 -1 (-1850 3450)(-3125 3450);
FORCEPROP 2 LAST SIG_NAME H_CPU0_ERR0_G_N
J 0
(-2875 3460);
DISPLAY 0.617021 (-2875 3460);
PAINT ORANGE (-2875 3460);
WIRE 16 -1 (-1850 3500)(-3125 3500);
FORCEPROP 2 LAST SIG_NAME H_CPU0_ERR1_G_N
J 0
(-2875 3510);
DISPLAY 0.617021 (-2875 3510);
PAINT ORANGE (-2875 3510);
WIRE 16 -1 (-1850 3550)(-3125 3550);
FORCEPROP 2 LAST SIG_NAME H_CPU0_ERR2_G_N
J 0
(-2875 3560);
DISPLAY 0.617021 (-2875 3560);
PAINT ORANGE (-2875 3560);
WIRE 16 -1 (-3125 3650)(-1875 3650);
FORCEPROP 2 LAST SIG_NAME H_CPU0_CATERR_G_N
J 0
(-2875 3660);
DISPLAY 0.617021 (-2875 3660);
PAINT ORANGE (-2875 3660);
WIRE 16 -1 (-1850 1750)(-3125 1750);
FORCEPROP 2 LAST SIG_NAME PD_PIROM_CPU0_ADDR1
J 0
(-2925 1760);
DISPLAY 0.617021 (-2925 1760);
PAINT ORANGE (-2925 1760);
WIRE 16 -1 (-1850 1800)(-3125 1800);
FORCEPROP 2 LAST SIG_NAME PD_PIROM_CPU0_ADDR2
J 0
(-2925 1810);
DISPLAY 0.617021 (-2925 1810);
PAINT ORANGE (-2925 1810);
WIRE 16 -1 (-1875 1350)(-3125 1350);
FORCEPROP 2 LAST SIG_NAME XDP_CPU_PRDY_N
J 0
(-2900 1360);
DISPLAY 0.617021 (-2900 1360);
PAINT ORANGE (-2900 1360);
WIRE 16 -1 (-1875 1400)(-3125 1400);
FORCEPROP 2 LAST SIG_NAME XDP_CPU_PREQ_N
J 0
(-2900 1410);
DISPLAY 0.617021 (-2900 1410);
PAINT ORANGE (-2900 1410);
WIRE 16 -1 (-1850 1500)(-3125 1500);
FORCEPROP 2 LAST SIG_NAME PD_CPU0_TEST12
J 0
(-2925 1510);
DISPLAY 0.617021 (-2925 1510);
PAINT ORANGE (-2925 1510);
WIRE 16 -1 (-1850 1900)(-3125 1900);
FORCEPROP 2 LAST SIG_NAME PU_CPU0_LEGACY_SKT
J 0
(-2925 1910);
DISPLAY 0.617021 (-2925 1910);
PAINT ORANGE (-2925 1910);
WIRE 16 -1 (-1850 2100)(-3125 2100);
FORCEPROP 2 LAST SIG_NAME PU_CPU0_TSC_SYNC
J 0
(-2923 2115);
DISPLAY 0.617021 (-2923 2115);
PAINT ORANGE (-2923 2115);
WIRE 16 -1 (-3125 3350)(-1875 3350);
FORCEPROP 2 LAST SIG_NAME H_CPU0_MSMI_G_N
J 0
(-2875 3360);
DISPLAY 0.617021 (-2875 3360);
PAINT ORANGE (-2875 3360);
WIRE 16 -1 (-2675 700)(-550 700);
WIRE 16 -1 (-2675 625)(-525 625);
WIRE 16 -1 (-3125 3250)(-1850 3250);
FORCEPROP 2 LAST SIG_NAME TP_CPU0_PROCDIS_G_N
J 0
(-2875 3260);
DISPLAY 0.617021 (-2875 3260);
PAINT ORANGE (-2875 3260);
FORCEPROP 2 LASTPROP $XRERR UNIQUE?
J 0
(-1820 3250);
DISPLAY 0.638298 (-1820 3250);
PAINT MONO (-1820 3250);
DISPLAY INVISIBLE (-1820 3250);
WIRE 16 -1 (-2175 2750)(-3125 2750);
FORCEPROP 2 LAST SIG_NAME H_CPU0_FAST_WAKE_N
J 0
(-2875 2760);
DISPLAY 0.617021 (-2875 2760);
PAINT ORANGE (-2875 2760);
WIRE 16 -1 (-2150 2800)(-3125 2800);
FORCEPROP 2 LAST SIG_NAME PD_CPU0_BIST_ENABLE
J 0
(-2875 2810);
DISPLAY 0.617021 (-2875 2810);
PAINT ORANGE (-2875 2810);
WIRE 16 -1 (-2150 2850)(-3125 2850);
FORCEPROP 2 LAST SIG_NAME PD_CPU0_TXT_PLTEN
J 0
(-2875 2860);
DISPLAY 0.617021 (-2875 2860);
PAINT ORANGE (-2875 2860);
WIRE 16 -1 (-2150 2900)(-3125 2900);
FORCEPROP 2 LAST SIG_NAME PU_CPU0_TXT_AGENT
J 0
(-2875 2910);
DISPLAY 0.617021 (-2875 2910);
PAINT ORANGE (-2875 2910);
WIRE 16 -1 (-2150 2950)(-3125 2950);
FORCEPROP 2 LAST SIG_NAME H_CPU0_BMCINIT
J 0
(-2875 2960);
DISPLAY 0.617021 (-2875 2960);
PAINT ORANGE (-2875 2960);
WIRE 16 -1 (-2150 3000)(-3125 3000);
FORCEPROP 2 LAST SIG_NAME PU_CPU0_FRMAGENT
J 0
(-2875 3010);
DISPLAY 0.617021 (-2875 3010);
PAINT ORANGE (-2875 3010);
WIRE 16 -1 (-3125 3050)(-2150 3050);
FORCEPROP 2 LAST SIG_NAME PU_CPU0_SAFE_MODE_BOOT
J 0
(-2875 3060);
DISPLAY 0.617021 (-2875 3060);
PAINT ORANGE (-2875 3060);
WIRE 16 -1 (-2125 2650)(-3125 2650);
FORCEPROP 2 LAST SIG_NAME PU_CPU0_SOCKET_ID_1
J 0
(-2925 2660);
DISPLAY 0.617021 (-2925 2660);
PAINT ORANGE (-2925 2660);
WIRE 16 -1 (-2125 2600)(-3125 2600);
FORCEPROP 2 LAST SIG_NAME PU_CPU0_SOCKET_ID_0
J 0
(-2925 2610);
DISPLAY 0.617021 (-2925 2610);
PAINT ORANGE (-2925 2610);
WIRE 16 -1 (-2200 2550)(-3125 2550);
FORCEPROP 2 LAST SIG_NAME TP_CPU0_SOCKET_ID_2
J 0
(-2925 2560);
DISPLAY 0.617021 (-2925 2560);
PAINT ORANGE (-2925 2560);
FORCEPROP 2 LASTPROP $XRERR UNIQUE?
J 0
(-2170 2550);
DISPLAY 0.638298 (-2170 2550);
PAINT MONO (-2170 2550);
DISPLAY INVISIBLE (-2170 2550);
WIRE 16 -1 (-2075 3850)(-3125 3850);
FORCEPROP 2 LAST SIG_NAME SVID_DIO0_CPU0
J 0
(-2875 3860);
DISPLAY 0.617021 (-2875 3860);
PAINT ORANGE (-2875 3860);
FORCEPROP 2 LASTPROP $XRERR UNIQUE?
J 0
(-3115 3860);
DISPLAY 0.638298 (-3115 3860);
PAINT MONO (-3115 3860);
DISPLAY INVISIBLE (-3115 3860);
WIRE 16 -1 (-2075 3900)(-3125 3900);
FORCEPROP 2 LAST SIG_NAME SVID_ALERT1_CPU0_N
J 0
(-2875 3910);
DISPLAY 0.617021 (-2875 3910);
PAINT ORANGE (-2875 3910);
FORCEPROP 2 LASTPROP $XRERR UNIQUE?
J 0
(-3115 3910);
DISPLAY 0.638298 (-3115 3910);
PAINT MONO (-3115 3910);
DISPLAY INVISIBLE (-3115 3910);
WIRE 16 -1 (-2075 3950)(-3125 3950);
FORCEPROP 2 LAST SIG_NAME SVID_CLK1_CPU0
J 0
(-2875 3960);
DISPLAY 0.617021 (-2875 3960);
PAINT ORANGE (-2875 3960);
FORCEPROP 2 LASTPROP $XRERR UNIQUE?
J 0
(-3115 3960);
DISPLAY 0.638298 (-3115 3960);
PAINT MONO (-3115 3960);
DISPLAY INVISIBLE (-3115 3960);
WIRE 16 -1 (-2075 4000)(-3125 4000);
FORCEPROP 2 LAST SIG_NAME SVID_DIO1_CPU0
J 0
(-2875 4010);
DISPLAY 0.617021 (-2875 4010);
PAINT ORANGE (-2875 4010);
FORCEPROP 2 LASTPROP $XRERR UNIQUE?
J 0
(-3115 4010);
DISPLAY 0.638298 (-3115 4010);
PAINT MONO (-3115 4010);
DISPLAY INVISIBLE (-3115 4010);
WIRE 16 -1 (-2075 3800)(-3125 3800);
FORCEPROP 2 LAST SIG_NAME SVID_CLK0_CPU0
J 0
(-2875 3810);
DISPLAY 0.617021 (-2875 3810);
PAINT ORANGE (-2875 3810);
FORCEPROP 2 LASTPROP $XRERR UNIQUE?
J 0
(-3115 3810);
DISPLAY 0.638298 (-3115 3810);
PAINT MONO (-3115 3810);
DISPLAY INVISIBLE (-3115 3810);
WIRE 16 -1 (-2075 3750)(-3125 3750);
FORCEPROP 2 LAST SIG_NAME SVID_ALERT0_CPU0_N
J 0
(-2875 3760);
DISPLAY 0.617021 (-2875 3760);
PAINT ORANGE (-2875 3760);
FORCEPROP 2 LASTPROP $XRERR UNIQUE?
J 0
(-3115 3760);
DISPLAY 0.638298 (-3115 3760);
PAINT MONO (-3115 3760);
DISPLAY INVISIBLE (-3115 3760);
WIRE 16 -1 (-2275 1000)(-2275 575);
WIRE 16 -1 (-5025 4300)(-6300 4300);
FORCEPROP 2 LAST SIG_NAME CLK_100M_CPU0_BCLK1_DN
J 0
(-6275 4310);
DISPLAY 0.617021 (-6275 4310);
PAINT ORANGE (-6275 4310);
WIRE 16 -1 (-5025 4350)(-6300 4350);
FORCEPROP 2 LAST SIG_NAME CLK_100M_CPU0_BCLK1_DP
J 0
(-6275 4360);
DISPLAY 0.617021 (-6275 4360);
PAINT ORANGE (-6275 4360);
WIRE 16 -1 (-5025 4450)(-6300 4450);
FORCEPROP 2 LAST SIG_NAME CLK_100M_CPU0_BCLK0_DN
J 0
(-6275 4460);
DISPLAY 0.617021 (-6275 4460);
PAINT ORANGE (-6275 4460);
WIRE 16 -1 (-5025 4500)(-6300 4500);
FORCEPROP 2 LAST SIG_NAME CLK_100M_CPU0_BCLK0_DP
J 0
(-6275 4510);
DISPLAY 0.617021 (-6275 4510);
PAINT ORANGE (-6275 4510);
WIRE 16 -1 (-5025 4150)(-6300 4150);
FORCEPROP 2 LAST SIG_NAME CLK_100M_CPU0_BCLK2_DN
J 0
(-6275 4160);
DISPLAY 0.617021 (-6275 4160);
PAINT ORANGE (-6275 4160);
WIRE 16 -1 (-5025 4200)(-6300 4200);
FORCEPROP 2 LAST SIG_NAME CLK_100M_CPU0_BCLK2_DP
J 0
(-6275 4210);
DISPLAY 0.617021 (-6275 4210);
PAINT ORANGE (-6275 4210);
WIRE 16 -1 (-5975 2750)(-5025 2750);
FORCEPROP 2 LAST SIG_NAME SMB_DDR_ABC_SCL_G_R
J 0
(-5950 2760);
DISPLAY 0.617021 (-5950 2760);
PAINT ORANGE (-5950 2760);
WIRE 16 -1 (-5025 2800)(-5975 2800);
FORCEPROP 2 LAST SIG_NAME SMB_DDR_DEF_SCL_G_R
J 0
(-5950 2810);
DISPLAY 0.617021 (-5950 2810);
PAINT ORANGE (-5950 2810);
WIRE 16 -1 (-5025 2850)(-5975 2850);
FORCEPROP 2 LAST SIG_NAME SMB_DDR_ABC_SDA_G_R
J 0
(-5950 2860);
DISPLAY 0.617021 (-5950 2860);
PAINT ORANGE (-5950 2860);
WIRE 16 -1 (-5025 2900)(-5975 2900);
FORCEPROP 2 LAST SIG_NAME SMB_DDR_DEF_SDA_G_R
J 0
(-5950 2910);
DISPLAY 0.617021 (-5950 2910);
PAINT ORANGE (-5950 2910);
WIRE 16 -1 (-5025 3900)(-6300 3900);
FORCEPROP 2 LAST SIG_NAME M_ABC_RST_N
J 0
(-6275 3910);
DISPLAY 0.617021 (-6275 3910);
PAINT ORANGE (-6275 3910);
WIRE 16 -1 (-5025 4000)(-6300 4000);
FORCEPROP 2 LAST SIG_NAME PWRGD_CPU0_DRAMPWROK_DEF_G
J 0
(-6275 4010);
DISPLAY 0.617021 (-6275 4010);
PAINT ORANGE (-6275 4010);
WIRE 16 -1 (-5025 4050)(-6300 4050);
FORCEPROP 2 LAST SIG_NAME PWRGD_CPU0_DRAMPWROK_ABC_G
J 0
(-6275 4060);
DISPLAY 0.617021 (-6275 4060);
PAINT ORANGE (-6275 4060);
WIRE 16 -1 (-5025 1200)(-6325 1200);
FORCEPROP 2 LAST SIG_NAME XDP_CPU_TRST_N
J 0
(-6300 1210);
DISPLAY 0.617021 (-6300 1210);
PAINT ORANGE (-6300 1210);
WIRE 16 -1 (-6325 1250)(-5025 1250);
FORCEPROP 2 LAST SIG_NAME XDP_CPU_TMS
J 0
(-6300 1260);
DISPLAY 0.617021 (-6300 1260);
PAINT ORANGE (-6300 1260);
WIRE 16 -1 (-6325 1300)(-5025 1300);
FORCEPROP 2 LAST SIG_NAME XDP_CPU_TCK0
J 0
(-6300 1310);
DISPLAY 0.617021 (-6300 1310);
PAINT ORANGE (-6300 1310);
WIRE 16 -1 (-5025 1350)(-6325 1350);
FORCEPROP 2 LAST SIG_NAME XDP_CPU_TDI
J 0
(-6300 1360);
DISPLAY 0.617021 (-6300 1360);
PAINT ORANGE (-6300 1360);
WIRE 16 -1 (-6325 1450)(-5025 1450);
FORCEPROP 2 LAST SIG_NAME XDP_CPU_MBP0_N
J 0
(-6300 1460);
DISPLAY 0.617021 (-6300 1460);
PAINT ORANGE (-6300 1460);
WIRE 16 -1 (-6325 1500)(-5025 1500);
FORCEPROP 2 LAST SIG_NAME XDP_CPU_MBP1_N
J 0
(-6300 1510);
DISPLAY 0.617021 (-6300 1510);
PAINT ORANGE (-6300 1510);
WIRE 16 -1 (-5025 2450)(-6275 2450);
FORCEPROP 2 LAST SIG_NAME SMB_PIROM_CPU0_SDA
J 0
(-6250 2460);
DISPLAY 0.617021 (-6250 2460);
PAINT ORANGE (-6250 2460);
WIRE 16 -1 (-5025 2500)(-6275 2500);
FORCEPROP 2 LAST SIG_NAME SMB_PIROM_CPU0_SCL
J 0
(-6250 2510);
DISPLAY 0.617021 (-6250 2510);
PAINT ORANGE (-6250 2510);
WIRE 16 -1 (-6325 1750)(-5025 1750);
FORCEPROP 2 LAST SIG_NAME XDP_CPU_OBSFN_B0_MBP6_N
J 0
(-6300 1760);
DISPLAY 0.617021 (-6300 1760);
PAINT ORANGE (-6300 1760);
WIRE 16 -1 (-6300 3450)(-5025 3450);
FORCEPROP 2 LAST SIG_NAME M_C_CPU_VREF
J 0
(-6275 3460);
DISPLAY 0.617021 (-6275 3460);
PAINT ORANGE (-6275 3460);
WIRE 16 -1 (-6300 3400)(-5025 3400);
FORCEPROP 2 LAST SIG_NAME M_B_CPU_VREF
J 0
(-6275 3410);
DISPLAY 0.617021 (-6275 3410);
PAINT ORANGE (-6275 3410);
WIRE 16 -1 (-5025 3550)(-6300 3550);
FORCEPROP 2 LAST SIG_NAME M_E_CPU_VREF
J 0
(-6275 3560);
DISPLAY 0.617021 (-6275 3560);
PAINT ORANGE (-6275 3560);
WIRE 16 -1 (-6300 3600)(-5025 3600);
FORCEPROP 2 LAST SIG_NAME M_F_CPU_VREF
J 0
(-6275 3610);
DISPLAY 0.617021 (-6275 3610);
PAINT ORANGE (-6275 3610);
WIRE 16 -1 (-6300 3350)(-5025 3350);
FORCEPROP 2 LAST SIG_NAME M_A_CPU_VREF
J 0
(-6275 3360);
DISPLAY 0.617021 (-6275 3360);
PAINT ORANGE (-6275 3360);
WIRE 16 -1 (-6325 1800)(-5025 1800);
FORCEPROP 2 LAST SIG_NAME XDP_CPU_OBSFN_B1_MBP7_N
J 0
(-6300 1810);
DISPLAY 0.617021 (-6300 1810);
PAINT ORANGE (-6300 1810);
WIRE 16 -1 (-5025 3500)(-6300 3500);
FORCEPROP 2 LAST SIG_NAME M_D_CPU_VREF
J 0
(-6275 3510);
DISPLAY 0.617021 (-6275 3510);
PAINT ORANGE (-6275 3510);
WIRE 16 -1 (-5025 3700)(-6275 3700);
FORCEPROP 2 LAST SIG_NAME H_CPU0_MEMDEF_MEMHOT_G_N
J 0
(-6250 3710);
DISPLAY 0.617021 (-6250 3710);
PAINT ORANGE (-6250 3710);
WIRE 16 -1 (-5025 3750)(-6275 3750);
FORCEPROP 2 LAST SIG_NAME H_CPU0_MEMABC_MEMHOT_G_N
J 0
(-6250 3760);
DISPLAY 0.617021 (-6250 3760);
PAINT ORANGE (-6250 3760);
WIRE 16 -1 (-5025 3850)(-6300 3850);
FORCEPROP 2 LAST SIG_NAME M_DEF_RST_N
J 0
(-6275 3860);
DISPLAY 0.617021 (-6275 3860);
PAINT ORANGE (-6275 3860);
WIRE 16 -1 (-5025 3050)(-6875 3050);
FORCEPROP 2 LAST SIG_NAME A_CPU0_DEF_RCOMP1
J 0
(-6250 3060);
DISPLAY 0.617021 (-6250 3060);
PAINT ORANGE (-6250 3060);
FORCEPROP 2 LASTPROP $XRERR UNIQUE?
J 0
(-6490 3060);
DISPLAY 0.638298 (-6490 3060);
PAINT MONO (-6490 3060);
DISPLAY INVISIBLE (-6490 3060);
WIRE 16 -1 (-6875 3025)(-6875 3050);
WIRE 16 -1 (-5025 3100)(-7125 3100);
FORCEPROP 2 LAST SIG_NAME A_CPU0_DEF_RCOMP2
J 0
(-6250 3110);
DISPLAY 0.617021 (-6250 3110);
PAINT ORANGE (-6250 3110);
FORCEPROP 2 LASTPROP $XRERR UNIQUE?
J 0
(-6490 3110);
DISPLAY 0.638298 (-6490 3110);
PAINT MONO (-6490 3110);
DISPLAY INVISIBLE (-6490 3110);
WIRE 16 -1 (-7125 3025)(-7125 3100);
WIRE 16 -1 (-5025 3150)(-7350 3150);
FORCEPROP 2 LAST SIG_NAME A_CPU0_ABC_RCOMP0
J 0
(-6250 3160);
DISPLAY 0.617021 (-6250 3160);
PAINT ORANGE (-6250 3160);
FORCEPROP 2 LASTPROP $XRERR UNIQUE?
J 0
(-6490 3160);
DISPLAY 0.638298 (-6490 3160);
PAINT MONO (-6490 3160);
DISPLAY INVISIBLE (-6490 3160);
WIRE 16 -1 (-7350 3025)(-7350 3150);
WIRE 16 -1 (-5025 3000)(-6625 3000);
FORCEPROP 2 LAST SIG_NAME A_CPU0_DEF_RCOMP0
J 0
(-6250 3010);
DISPLAY 0.617021 (-6250 3010);
PAINT ORANGE (-6250 3010);
FORCEPROP 2 LASTPROP $XRERR UNIQUE?
J 0
(-6490 3010);
DISPLAY 0.638298 (-6490 3010);
PAINT MONO (-6490 3010);
DISPLAY INVISIBLE (-6490 3010);
WIRE 16 -1 (-6625 2975)(-6625 3000);
WIRE 16 -1 (-5025 2600)(-6300 2600);
FORCEPROP 2 LAST SIG_NAME TP_CPU0_PE_HP_SDA
J 0
(-6275 2610);
DISPLAY 0.617021 (-6275 2610);
PAINT ORANGE (-6275 2610);
FORCEPROP 2 LASTPROP $XRERR UNIQUE?
J 0
(-6540 2600);
DISPLAY 0.638298 (-6540 2600);
PAINT MONO (-6540 2600);
DISPLAY INVISIBLE (-6540 2600);
WIRE 16 -1 (-5025 3250)(-7800 3250);
FORCEPROP 2 LAST SIG_NAME A_CPU0_ABC_RCOMP2
J 0
(-6250 3260);
DISPLAY 0.617021 (-6250 3260);
PAINT ORANGE (-6250 3260);
FORCEPROP 2 LASTPROP $XRERR UNIQUE?
J 0
(-6490 3260);
DISPLAY 0.638298 (-6490 3260);
PAINT MONO (-6490 3260);
DISPLAY INVISIBLE (-6490 3260);
WIRE 16 -1 (-7800 3100)(-7800 3250);
WIRE 16 -1 (-5025 3200)(-7575 3200);
FORCEPROP 2 LAST SIG_NAME A_CPU0_ABC_RCOMP1
J 0
(-6250 3210);
DISPLAY 0.617021 (-6250 3210);
PAINT ORANGE (-6250 3210);
FORCEPROP 2 LASTPROP $XRERR UNIQUE?
J 0
(-6490 3210);
DISPLAY 0.638298 (-6490 3210);
PAINT MONO (-6490 3210);
DISPLAY INVISIBLE (-6490 3210);
WIRE 16 -1 (-7575 3100)(-7575 3200);
WIRE 16 -1 (-5025 2300)(-5275 2300);
WIRE 16 -1 (-5275 2300)(-5275 2350);
WIRE 16 -1 (-5275 2350)(-5025 2350);
WIRE 16 -1 (-7800 2350)(-5275 2350);
FORCEPROP 2 LAST SIG_NAME A_CPU0_PE3_RBIAS
J 0
(-6525 2360);
DISPLAY 0.617021 (-6525 2360);
PAINT ORANGE (-6525 2360);
FORCEPROP 2 LASTPROP $XRERR UNIQUE?
J 0
(-6765 2360);
DISPLAY 0.638298 (-6765 2360);
PAINT MONO (-6765 2360);
DISPLAY INVISIBLE (-6765 2360);
WIRE 16 -1 (-7800 2350)(-7800 2200);
WIRE 16 -1 (-5025 2200)(-5350 2200);
WIRE 16 -1 (-5350 2200)(-5350 2250);
WIRE 16 -1 (-5025 2250)(-5350 2250);
WIRE 16 -1 (-5350 2250)(-5350 2300);
WIRE 16 -1 (-5350 2300)(-7575 2300);
FORCEPROP 2 LAST SIG_NAME A_CPU0_PE012_RBIAS
J 0
(-6525 2310);
DISPLAY 0.617021 (-6525 2310);
PAINT ORANGE (-6525 2310);
FORCEPROP 2 LASTPROP $XRERR UNIQUE?
J 0
(-6765 2310);
DISPLAY 0.638298 (-6765 2310);
PAINT MONO (-6765 2310);
DISPLAY INVISIBLE (-6765 2310);
WIRE 16 -1 (-7575 2200)(-7575 2300);
WIRE 16 -1 (-5025 2650)(-6300 2650);
FORCEPROP 2 LAST SIG_NAME TP_CPU0_PE_HP_SCL
J 0
(-6275 2660);
DISPLAY 0.617021 (-6275 2660);
PAINT ORANGE (-6275 2660);
FORCEPROP 2 LASTPROP $XRERR UNIQUE?
J 0
(-6540 2650);
DISPLAY 0.638298 (-6540 2650);
PAINT MONO (-6540 2650);
DISPLAY INVISIBLE (-6540 2650);
WIRE 16 -1 (-5425 2100)(-5025 2100);
WIRE 16 -1 (-5425 2150)(-5425 2100);
WIRE 16 -1 (-5025 2150)(-5425 2150);
WIRE 16 -1 (-5425 2150)(-5425 2250);
WIRE 16 -1 (-7375 2250)(-5425 2250);
FORCEPROP 2 LAST SIG_NAME A_CPU0_UPI01_RBIAS
J 0
(-6525 2260);
DISPLAY 0.617021 (-6525 2260);
PAINT ORANGE (-6525 2260);
FORCEPROP 2 LASTPROP $XRERR UNIQUE?
J 0
(-6765 2260);
DISPLAY 0.638298 (-6765 2260);
PAINT MONO (-6765 2260);
DISPLAY INVISIBLE (-6765 2260);
WIRE 16 -1 (-7375 2200)(-7375 2250);
WIRE 16 -1 (-5575 1900)(-5025 1900);
WIRE 16 -1 (-5575 1950)(-5575 1900);
WIRE 16 -1 (-5575 1950)(-5575 2150);
WIRE 16 -1 (-5025 1950)(-5575 1950);
WIRE 16 -1 (-6925 2150)(-5575 2150);
FORCEPROP 2 LAST SIG_NAME A_CPU0_MCP01_RBIAS
J 0
(-6525 2160);
DISPLAY 0.617021 (-6525 2160);
PAINT ORANGE (-6525 2160);
FORCEPROP 2 LASTPROP $XRERR UNIQUE?
J 0
(-6765 2160);
DISPLAY 0.638298 (-6765 2160);
PAINT MONO (-6765 2160);
DISPLAY INVISIBLE (-6765 2160);
WIRE 16 -1 (-6925 2100)(-6925 2150);
WIRE 16 -1 (-5025 2050)(-5500 2050);
WIRE 16 -1 (-5500 2050)(-5500 2200);
WIRE 16 -1 (-5500 2050)(-5500 2000);
WIRE 16 -1 (-5500 2000)(-5025 2000);
WIRE 16 -1 (-7150 2200)(-5500 2200);
FORCEPROP 2 LAST SIG_NAME A_CPU0_UPI2_RBIAS
J 0
(-6525 2210);
DISPLAY 0.617021 (-6525 2210);
PAINT ORANGE (-6525 2210);
FORCEPROP 2 LASTPROP $XRERR UNIQUE?
J 0
(-6765 2210);
DISPLAY 0.638298 (-6765 2210);
PAINT MONO (-6765 2210);
DISPLAY INVISIBLE (-6765 2210);
WIRE 16 -1 (-7150 2150)(-7150 2200);
WIRE 16 -1 (-6325 1700)(-5025 1700);
FORCEPROP 2 LAST SIG_NAME TP_XDP_CPU0_OBSDATA_A3_MBP5_N
J 0
(-6300 1710);
DISPLAY 0.617021 (-6300 1710);
PAINT ORANGE (-6300 1710);
FORCEPROP 2 LASTPROP $XRERR UNIQUE?
J 0
(-6565 1700);
DISPLAY 0.638298 (-6565 1700);
PAINT MONO (-6565 1700);
DISPLAY INVISIBLE (-6565 1700);
WIRE 16 -1 (-6325 1650)(-5025 1650);
FORCEPROP 2 LAST SIG_NAME TP_XDP_CPU0_OBSDATA_A2_MBP4_N
J 0
(-6300 1660);
DISPLAY 0.617021 (-6300 1660);
PAINT ORANGE (-6300 1660);
FORCEPROP 2 LASTPROP $XRERR UNIQUE?
J 0
(-6565 1650);
DISPLAY 0.638298 (-6565 1650);
PAINT MONO (-6565 1650);
DISPLAY INVISIBLE (-6565 1650);
WIRE 16 -1 (-6325 1600)(-5025 1600);
FORCEPROP 2 LAST SIG_NAME TP_XDP_CPU0_OBSDATA_A1_MBP3_N
J 0
(-6300 1610);
DISPLAY 0.617021 (-6300 1610);
PAINT ORANGE (-6300 1610);
FORCEPROP 2 LASTPROP $XRERR UNIQUE?
J 0
(-6565 1600);
DISPLAY 0.638298 (-6565 1600);
PAINT MONO (-6565 1600);
DISPLAY INVISIBLE (-6565 1600);
WIRE 16 -1 (-6325 1550)(-5025 1550);
FORCEPROP 2 LAST SIG_NAME TP_XDP_CPU0_OBSDATA_A0_MBP2_N
J 0
(-6300 1560);
DISPLAY 0.617021 (-6300 1560);
PAINT ORANGE (-6300 1560);
FORCEPROP 2 LASTPROP $XRERR UNIQUE?
J 0
(-6565 1550);
DISPLAY 0.638298 (-6565 1550);
PAINT MONO (-6565 1550);
DISPLAY INVISIBLE (-6565 1550);
WIRE 16 -1 (-600 2400)(-1275 2400);
WIRE 16 -1 (-1275 2600)(-1275 2400);
WIRE 16 -1 (-1275 2400)(-3125 2400);
FORCEPROP 2 LAST SIG_NAME FM_CPU0_PROC_ID0
J 0
(-2925 2410);
DISPLAY 0.617021 (-2925 2410);
PAINT ORANGE (-2925 2410);
WIRE 16 -1 (-1850 2050)(-3125 2050);
FORCEPROP 2 LAST SIG_NAME FM_CPU0_SM_WP
J 0
(-2925 2060);
DISPLAY 0.617021 (-2925 2060);
PAINT ORANGE (-2925 2060);
WIRE 16 -1 (-1850 1700)(-3125 1700);
FORCEPROP 2 LAST SIG_NAME PD_PIROM_CPU0_ADDR0
J 0
(-2925 1710);
DISPLAY 0.617021 (-2925 1710);
PAINT ORANGE (-2925 1710);
WIRE 16 -1 (-1850 1150)(-3125 1150);
FORCEPROP 2 LAST SIG_NAME XDP_CPU0_TDO
J 0
(-2900 1160);
DISPLAY 0.617021 (-2900 1160);
PAINT ORANGE (-2900 1160);
WIRE 16 -1 (-600 1250)(-1075 1250);
WIRE 16 -1 (-1075 1350)(-1075 1250);
WIRE 16 -1 (-1075 1250)(-3125 1250);
FORCEPROP 2 LAST SIG_NAME FM_CPU0_SKTOCC_LVT3_N
J 0
(-2900 1260);
DISPLAY 0.617021 (-2900 1260);
PAINT ORANGE (-2900 1260);
WIRE 16 -1 (-1850 1950)(-3125 1950);
FORCEPROP 2 LAST SIG_NAME TP_NMI_CPU0
J 0
(-2925 1960);
DISPLAY 0.617021 (-2925 1960);
PAINT ORANGE (-2925 1960);
FORCEPROP 2 LASTPROP $XRERR UNIQUE?
J 0
(-1820 1950);
DISPLAY 0.638298 (-1820 1950);
PAINT MONO (-1820 1950);
DISPLAY INVISIBLE (-1820 1950);
WIRE 16 -1 (-600 2300)(-1075 2300);
WIRE 16 -1 (-1075 2600)(-1075 2300);
WIRE 16 -1 (-1075 2300)(-3125 2300);
FORCEPROP 2 LAST SIG_NAME FM_CPU0_PKGID2
J 0
(-2925 2310);
DISPLAY 0.617021 (-2925 2310);
PAINT ORANGE (-2925 2310);
WIRE 16 -1 (-875 2600)(-875 2250);
WIRE 16 -1 (-600 2250)(-875 2250);
WIRE 16 -1 (-875 2250)(-3125 2250);
FORCEPROP 2 LAST SIG_NAME FM_CPU0_PKGID1
J 0
(-2925 2260);
DISPLAY 0.617021 (-2925 2260);
PAINT ORANGE (-2925 2260);
WIRE 16 -1 (-600 2200)(-675 2200);
WIRE 16 -1 (-675 2600)(-675 2200);
WIRE 16 -1 (-3125 2200)(-675 2200);
FORCEPROP 2 LAST SIG_NAME FM_CPU0_PKGID0
J 0
(-2925 2210);
DISPLAY 0.617021 (-2925 2210);
PAINT ORANGE (-2925 2210);
WIRE 16 -1 (-2725 550)(-475 550);
WIRE 16 -1 (-2725 1025)(-2725 550);
WIRE 16 -1 (-475 550)(-475 1025);
WIRE 16 -1 (-2725 1025)(-475 1025);
WIRE 16 -1 (-2675 825)(-525 825);
WIRE 16 -1 (-2675 900)(-525 900);
WIRE 16 -1 (-1850 1550)(-3125 1550);
FORCEPROP 2 LAST SIG_NAME PD_CPU0_TEST13
J 0
(-2925 1560);
DISPLAY 0.617021 (-2925 1560);
PAINT ORANGE (-2925 1560);
WIRE 16 -1 (-3125 1650)(-1850 1650);
FORCEPROP 2 LAST SIG_NAME PD_CPU0_KSFC_DIS
J 0
(-2915 1652);
DISPLAY 0.617021 (-2915 1652);
PAINT ORANGE (-2915 1652);
WIRE 16 -1 (-3125 1600)(-1850 1600);
FORCEPROP 2 LAST SIG_NAME PD_CPU0_TEST14
J 0
(-2925 1610);
DISPLAY 0.617021 (-2925 1610);
PAINT ORANGE (-2925 1610);
DOT 1 (-675 2925);
DOT 1 (-5275 2350);
DOT 1 (-7150 1850);
DOT 1 (-1075 1250);
DOT 1 (-7800 2700);
DOT 1 (-1200 4000);
DOT 1 (-6875 2700);
DOT 1 (-7575 2700);
DOT 1 (-5575 1950);
DOT 1 (-5500 2050);
DOT 1 (-5425 2150);
DOT 1 (-7575 1850);
DOT 1 (-7350 2700);
DOT 1 (-975 4525);
DOT 1 (-975 3900);
DOT 1 (-975 3750);
DOT 1 (-1200 3850);
DOT 1 (-1075 2925);
DOT 1 (-875 2250);
DOT 1 (-675 2200);
DOT 1 (-1275 2400);
DOT 1 (-975 3225);
DOT 1 (-7800 1850);
DOT 1 (-1075 2300);
DOT 1 (-7375 1850);
DOT 1 (-1475 2450);
DOT 1 (-7125 2700);
DOT 1 (-5350 2250);
DOT 1 (-875 2925);
DOT 1 (-1275 2925);
FORCENOTE
PIROM_ADDR[2:0] 3B000
(-1275 1875) 0;
DISPLAY LEFT (-1275 1875);
DISPLAY 0.808511 (-1275 1875);
PAINT PURPLE (-1275 1875);
FORCENOTE
PKG_ID[2:0]
(-1475 950) 0;
DISPLAY LEFT (-1475 950);
DISPLAY 0.808511 (-1475 950);
PAINT PURPLE (-1475 950);
FORCENOTE
NON-MCP SUPPORT
(-1025 850) 0;
DISPLAY LEFT (-1025 850);
DISPLAY 0.638298 (-1025 850);
PAINT PURPLE (-1025 850);
FORCENOTE
DEFINITION
(-900 950) 0;
DISPLAY LEFT (-900 950);
DISPLAY 0.808511 (-900 950);
PAINT PURPLE (-900 950);
FORCENOTE
RESERVED
(-1000 650) 0;
DISPLAY LEFT (-1000 650);
DISPLAY 0.638298 (-1000 650);
PAINT PURPLE (-1000 650);
FORCENOTE
RESERVED
(-1000 575) 0;
DISPLAY LEFT (-1000 575);
DISPLAY 0.638298 (-1000 575);
PAINT PURPLE (-1000 575);
FORCENOTE
MCP SUPPORT
(-1025 725) 0;
DISPLAY LEFT (-1025 725);
DISPLAY 0.638298 (-1025 725);
PAINT PURPLE (-1025 725);
FORCENOTE
HOST FABRIC INTERFACE
(-1025 775) 0;
DISPLAY LEFT (-1025 775);
DISPLAY 0.638298 (-1025 775);
PAINT PURPLE (-1025 775);
FORCENOTE
3'B001
(-1450 750) 0;
DISPLAY LEFT (-1450 750);
DISPLAY 0.638298 (-1450 750);
PAINT PURPLE (-1450 750);
FORCENOTE
3'B010
(-1450 650) 0;
DISPLAY LEFT (-1450 650);
DISPLAY 0.638298 (-1450 650);
PAINT PURPLE (-1450 650);
FORCENOTE
3'B111-3'B011
(-1450 575) 0;
DISPLAY LEFT (-1450 575);
DISPLAY 0.638298 (-1450 575);
PAINT PURPLE (-1450 575);
FORCENOTE
3'B000
(-1450 850) 0;
DISPLAY LEFT (-1450 850);
DISPLAY 0.638298 (-1450 850);
PAINT PURPLE (-1450 850);
FORCENOTE
RESERVED FOR FUTURE PROCESSOR
(-2250 750) 0;
DISPLAY LEFT (-2250 750);
DISPLAY 0.638298 (-2250 750);
PAINT PURPLE (-2250 750);
FORCENOTE
RESERVED
(-2250 650) 0;
DISPLAY LEFT (-2250 650);
DISPLAY 0.638298 (-2250 650);
PAINT PURPLE (-2250 650);
FORCENOTE
RESERVED
(-2250 575) 0;
DISPLAY LEFT (-2250 575);
DISPLAY 0.638298 (-2250 575);
PAINT PURPLE (-2250 575);
FORCENOTE
SKYLAKE PROCESSOR 
(-2250 850) 0;
DISPLAY LEFT (-2250 850);
DISPLAY 0.638298 (-2250 850);
PAINT PURPLE (-2250 850);
FORCENOTE
DEFINITION
(-2075 950) 0;
DISPLAY LEFT (-2075 950);
DISPLAY 0.808511 (-2075 950);
PAINT PURPLE (-2075 950);
FORCENOTE
2'B01
(-2575 750) 0;
DISPLAY LEFT (-2575 750);
DISPLAY 0.638298 (-2575 750);
PAINT PURPLE (-2575 750);
FORCENOTE
2'B10
(-2575 650) 0;
DISPLAY LEFT (-2575 650);
DISPLAY 0.638298 (-2575 650);
PAINT PURPLE (-2575 650);
FORCENOTE
2'B11
(-2575 575) 0;
DISPLAY LEFT (-2575 575);
DISPLAY 0.638298 (-2575 575);
PAINT PURPLE (-2575 575);
FORCENOTE
2'B00
(-2575 850) 0;
DISPLAY LEFT (-2575 850);
DISPLAY 0.638298 (-2575 850);
PAINT PURPLE (-2575 850);
FORCENOTE
PROC_ID [1:0]
(-2675 950) 0;
DISPLAY LEFT (-2675 950);
DISPLAY 0.808511 (-2675 950);
PAINT PURPLE (-2675 950);
FORCENOTE
BOM_COST=PROC_SOCKET
(-7925 225) 0;
DISPLAY LEFT (-7925 225);
DISPLAY 0.808511 (-7925 225);
PAINT PURPLE (-7925 225);
FORCENOTE
ROOM=CPU0
(-7925 350) 0;
DISPLAY LEFT (-7925 350);
DISPLAY 0.808511 (-7925 350);
PAINT PURPLE (-7925 350);
FORCENOTE
ALTERNATE: H63715-002
(-7875 4675) 0;
DISPLAY LEFT (-7875 4675);
DISPLAY 0.808511 (-7875 4675);
PAINT PURPLE (-7875 4675);
QUIT
